FILE_TYPE = MACRO_DRAWING;
SET COLOR_WIRE YELLOW;
SET COLOR_PROP MONO;
SET COLOR_DOT WHITE;
SET COLOR_ARC YELLOW;
SET COLOR_BODY GREEN;
SET COLOR_NOTE MONO;
SET PROP_DISPLAY VALUE;
SET PAGE_NUMBER P222;
FORCEADD OFFPAGE..2
(5525 1925);
FORCEPROP 2 LAST $XR0 221 
J 0
(5714 1925);
DISPLAY 0.638298 (5714 1925);
PAINT MONO (5714 1925);
FORCEPROP 2 LAST $XR1 191 
J 0
(5834 1925);
DISPLAY 0.638298 (5834 1925);
PAINT MONO (5834 1925);
FORCEPROP 1 LAST COMMENT_BODY TRUE
J 0
(5480 1830);
DISPLAY 0.872340 (5480 1830);
PAINT GREEN (5480 1830);
DISPLAY INVISIBLE (5480 1830);
FORCEPROP 2 LAST CDS_LIB mstr_standard
J 0
(5525 1925);
DISPLAY 0.744681 (5525 1925);
PAINT MONO (5525 1925);
DISPLAY INVISIBLE (5525 1925);
FORCEPROP 2 LAST PATH I10
J 0
(5729 1962);
DISPLAY 1.021277 (5729 1962);
PAINT ORANGE (5729 1962);
DISPLAY INVISIBLE (5729 1962);
FORCEPROP 1 LAST OFFPAGE TRUE
J 0
(5850 1800);
DISPLAY 0.872340 (5850 1800);
PAINT GREEN (5850 1800);
DISPLAY INVISIBLE (5850 1800);
FORCEADD CAP..1
(4000 1725);
FORCEPROP 1 LASTPIN (4000 1625) $PN 2
J 0
(4010 1605);
DISPLAY 0.617021 (4010 1605);
PAINT WHITE (4010 1605);
FORCEPROP 1 LASTPIN (4000 1825) $PN 1
J 0
(4010 1805);
DISPLAY 0.617021 (4010 1805);
PAINT WHITE (4010 1805);
FORCEPROP 1 LAST LOCATION C4A12
J 0
(4050 1825);
DISPLAY 0.617021 (4050 1825);
PAINT AQUA (4050 1825);
FORCEPROP 1 LAST PART_NUMBER A36096-046
J 0
(4050 1575);
DISPLAY 0.617021 (4050 1575);
PAINT BLUE (4050 1575);
FORCEPROP 1 LAST VALUE 1000PF
J 0
(4050 1775);
DISPLAY 0.617021 (4050 1775);
PAINT SKYBLUE (4050 1775);
FORCEPROP 1 LAST TOLERANCE 10%
J 0
(4050 1675);
DISPLAY 0.617021 (4050 1675);
PAINT SKYBLUE (4050 1675);
FORCEPROP 1 LAST PACK_TYPE 0402LF
J 0
(4050 1525);
DISPLAY 0.617021 (4050 1525);
PAINT SKYBLUE (4050 1525);
FORCEPROP 1 LAST VOLTAGE 50V
J 0
(4050 1725);
DISPLAY 0.617021 (4050 1725);
PAINT SKYBLUE (4050 1725);
FORCEPROP 1 LAST MATERIAL X7R
J 0
(4050 1625);
DISPLAY 0.617021 (4050 1625);
PAINT SKYBLUE (4050 1625);
FORCEPROP 2 LAST CDS_LIB mstr_discrete
J 0
(4000 1725);
DISPLAY 0.744681 (4000 1725);
PAINT MONO (4000 1725);
DISPLAY INVISIBLE (4000 1725);
FORCEPROP 2 LAST CDS_LOCATION C4A12
J 0
(4050 1825);
DISPLAY 0.617021 (4050 1825);
PAINT AQUA (4050 1825);
DISPLAY INVISIBLE (4050 1825);
FORCEPROP 2 LAST ROOM VTT_DEF_PWR_VR
J 0
(4050 1875);
DISPLAY 1.021277 (4050 1875);
PAINT ORANGE (4050 1875);
DISPLAY INVISIBLE (4050 1875);
FORCEPROP 1 LAST PATH I12
J 0
(4050 1875);
DISPLAY 0.978723 (4050 1875);
PAINT WHITE (4050 1875);
DISPLAY INVISIBLE (4050 1875);
FORCEPROP 2 LAST SEC_TYPE 0402LF
J 0
(4050 1925);
DISPLAY 1.021277 (4050 1925);
PAINT ORANGE (4050 1925);
DISPLAY INVISIBLE (4050 1925);
FORCEPROP 2 LAST SEC 1
J 0
(4050 1925);
DISPLAY 0.680851 (4050 1925);
PAINT MONO (4050 1925);
DISPLAY INVISIBLE (4050 1925);
FORCEPROP 2 LAST BOM_COST MEM_VRD_VTT_DEF
J 0
(4050 1925);
DISPLAY 1.021277 (4050 1925);
PAINT ORANGE (4050 1925);
DISPLAY INVISIBLE (4050 1925);
FORCEADD GND..1
(4000 1475);
FORCEPROP 3 LASTPIN (4000 1525) SIG_NAME GND\g
J 0
(4010 1535);
DISPLAY 0.659574 (4010 1535);
PAINT MONO (4010 1535);
DISPLAY INVISIBLE (4010 1535);
FORCEPROP 1 LAST VOLTAGE 0.0V
J 0
(3955 1432);
DISPLAY 0.340426 (3955 1432);
PAINT SKYBLUE (3955 1432);
DISPLAY INVISIBLE (3955 1432);
FORCEPROP 1 LAST SIZE 1B
J 0
(4075 1425);
DISPLAY 0.893617 (4075 1425);
PAINT GREEN (4075 1425);
DISPLAY INVISIBLE (4075 1425);
FORCEPROP 2 LAST CDS_LIB mstr_symbols
J 0
(4000 1475);
DISPLAY 0.744681 (4000 1475);
PAINT MONO (4000 1475);
DISPLAY INVISIBLE (4000 1475);
FORCEPROP 1 LAST BODY_TYPE PLUMBING
J 0
(3955 1432);
DISPLAY 0.340426 (3955 1432);
PAINT GREEN (3955 1432);
DISPLAY INVISIBLE (3955 1432);
FORCEPROP 1 LAST PATH I13
J 0
(4075 1475);
DISPLAY 0.872340 (4075 1475);
PAINT AQUA (4075 1475);
DISPLAY INVISIBLE (4075 1475);
FORCEPROP 1 LAST HDL_POWER GND
J 0
(4000 1625);
DISPLAY 0.893617 (4000 1625);
PAINT GREEN (4000 1625);
DISPLAY INVISIBLE (4000 1625);
FORCEADD CAP..1
(4125 1125);
FORCEPROP 1 LAST PART_NUMBER C95333-002
R 1
J 0
(4075 975);
DISPLAY 0.617021 (4075 975);
PAINT BLUE (4075 975);
FORCEPROP 1 LAST PACK_TYPE 0805LF
J 0
(4175 975);
DISPLAY 0.617021 (4175 975);
PAINT SKYBLUE (4175 975);
FORCEPROP 1 LASTPIN (4125 1025) $PN 2
J 0
(4135 1005);
DISPLAY 0.617021 (4135 1005);
PAINT WHITE (4135 1005);
FORCEPROP 1 LAST LOCATION C4A1
J 0
(4175 1225);
DISPLAY 0.617021 (4175 1225);
PAINT AQUA (4175 1225);
FORCEPROP 1 LAST VALUE 22UF
J 0
(4175 1175);
DISPLAY 0.617021 (4175 1175);
PAINT SKYBLUE (4175 1175);
FORCEPROP 1 LAST TOLERANCE 20%
J 0
(4175 1075);
DISPLAY 0.617021 (4175 1075);
PAINT SKYBLUE (4175 1075);
FORCEPROP 1 LAST VOLTAGE 4V
J 0
(4175 1125);
DISPLAY 0.617021 (4175 1125);
PAINT SKYBLUE (4175 1125);
FORCEPROP 1 LAST MATERIAL X6S
J 0
(4175 1025);
DISPLAY 0.617021 (4175 1025);
PAINT SKYBLUE (4175 1025);
FORCEPROP 1 LASTPIN (4125 1225) $PN 1
J 0
(4135 1205);
DISPLAY 0.617021 (4135 1205);
PAINT WHITE (4135 1205);
FORCEPROP 2 LAST CDS_LIB mstr_discrete
J 0
(4125 1125);
PAINT ORANGE (4125 1125);
DISPLAY INVISIBLE (4125 1125);
FORCEPROP 2 LAST CDS_LOCATION C4A1
J 0
(4175 1225);
DISPLAY 0.617021 (4175 1225);
PAINT AQUA (4175 1225);
DISPLAY INVISIBLE (4175 1225);
FORCEPROP 1 LAST PATH I16
J 0
(4175 1275);
DISPLAY 0.978723 (4175 1275);
PAINT WHITE (4175 1275);
DISPLAY INVISIBLE (4175 1275);
FORCEPROP 2 LAST ROOM VTT_DEF_PWR_VR
J 0
(4195 1280);
DISPLAY 1.021277 (4195 1280);
PAINT ORANGE (4195 1280);
DISPLAY INVISIBLE (4195 1280);
FORCEPROP 2 LAST SEC_TYPE 0805LF
J 0
(4176 1345);
DISPLAY 1.021277 (4176 1345);
PAINT ORANGE (4176 1345);
DISPLAY INVISIBLE (4176 1345);
FORCEPROP 2 LAST BOM_COST MEM_VRD_VTT_DEF
J 0
(4195 1330);
DISPLAY 1.021277 (4195 1330);
PAINT ORANGE (4195 1330);
DISPLAY INVISIBLE (4195 1330);
FORCEPROP 2 LAST SEC 1
J 0
(4176 1345);
DISPLAY 0.680851 (4176 1345);
PAINT MONO (4176 1345);
DISPLAY INVISIBLE (4176 1345);
FORCEADD GND..1
(4125 725);
FORCEPROP 3 LASTPIN (4125 775) SIG_NAME GND\g
J 0
(4135 785);
DISPLAY 0.659574 (4135 785);
PAINT MONO (4135 785);
DISPLAY INVISIBLE (4135 785);
FORCEPROP 1 LAST VOLTAGE 0.0V
J 0
(4080 682);
DISPLAY 0.340426 (4080 682);
PAINT SKYBLUE (4080 682);
DISPLAY INVISIBLE (4080 682);
FORCEPROP 1 LAST BODY_TYPE PLUMBING
J 0
(4080 682);
DISPLAY 0.340426 (4080 682);
PAINT GREEN (4080 682);
DISPLAY INVISIBLE (4080 682);
FORCEPROP 1 LAST PATH I17
J 0
(4200 725);
DISPLAY 0.872340 (4200 725);
PAINT AQUA (4200 725);
DISPLAY INVISIBLE (4200 725);
FORCEPROP 1 LAST SIZE 1B
J 0
(4200 675);
DISPLAY 0.893617 (4200 675);
PAINT GREEN (4200 675);
DISPLAY INVISIBLE (4200 675);
FORCEPROP 2 LAST CDS_LIB mstr_symbols
J 0
(4125 725);
PAINT ORANGE (4125 725);
DISPLAY INVISIBLE (4125 725);
FORCEPROP 1 LAST HDL_POWER GND
J 0
(4125 875);
DISPLAY 0.893617 (4125 875);
PAINT GREEN (4125 875);
DISPLAY INVISIBLE (4125 875);
FORCEADD RES..2
(3575 2100);
FORCEPROP 1 LASTPIN (3575 2000) $PN 2
J 0
(3580 2010);
DISPLAY 0.617021 (3580 2010);
PAINT WHITE (3580 2010);
FORCEPROP 1 LAST PACK_TYPE 0402
J 0
(3615 1925);
DISPLAY 0.617021 (3615 1925);
PAINT SKYBLUE (3615 1925);
FORCEPROP 1 LAST PART_NUMBER G21796-016
J 0
(3615 1975);
DISPLAY 0.617021 (3615 1975);
PAINT BLUE (3615 1975);
FORCEPROP 1 LAST MATERIAL CHIP
J 0
(3615 2025);
DISPLAY 0.617021 (3615 2025);
PAINT SKYBLUE (3615 2025);
FORCEPROP 1 LASTPIN (3575 2200) $PN 1
J 0
(3580 2162);
DISPLAY 0.617021 (3580 2162);
PAINT WHITE (3580 2162);
FORCEPROP 1 LAST LOCATION R6L9
J 0
(3620 2225);
DISPLAY 0.617021 (3620 2225);
PAINT AQUA (3620 2225);
FORCEPROP 1 LAST VALUE 10.0K
J 0
(3620 2175);
DISPLAY 0.617021 (3620 2175);
PAINT SKYBLUE (3620 2175);
FORCEPROP 1 LAST TOLERANCE 1%
J 0
(3620 2125);
DISPLAY 0.617021 (3620 2125);
PAINT SKYBLUE (3620 2125);
FORCEPROP 1 LAST WATTAGE 1/16W
J 0
(3615 2075);
DISPLAY 0.617021 (3615 2075);
PAINT SKYBLUE (3615 2075);
FORCEPROP 2 LAST CDS_LIB mstr_discrete
J 0
(3575 2100);
PAINT ORANGE (3575 2100);
DISPLAY INVISIBLE (3575 2100);
FORCEPROP 2 LAST BOM_COST MEM_VRD_VTT_DEF
J 0
(3625 2325);
DISPLAY 1.021277 (3625 2325);
PAINT ORANGE (3625 2325);
DISPLAY INVISIBLE (3625 2325);
FORCEPROP 2 LAST SEC_TYPE 0402
J 0
(3625 2321);
DISPLAY 1.021277 (3625 2321);
PAINT ORANGE (3625 2321);
DISPLAY INVISIBLE (3625 2321);
FORCEPROP 2 LAST SEC 1
J 0
(3625 2321);
DISPLAY 0.680851 (3625 2321);
PAINT MONO (3625 2321);
DISPLAY INVISIBLE (3625 2321);
FORCEPROP 2 LAST CDS_LOCATION R6L9
J 0
(3620 2225);
DISPLAY 0.617021 (3620 2225);
PAINT AQUA (3620 2225);
DISPLAY INVISIBLE (3620 2225);
FORCEPROP 1 LAST PATH I19
J 0
(3625 2275);
DISPLAY 0.978723 (3625 2275);
PAINT WHITE (3625 2275);
DISPLAY INVISIBLE (3625 2275);
FORCEPROP 2 LAST ROOM VTT_DEF_PWR_VR
J 0
(3625 2275);
DISPLAY 1.021277 (3625 2275);
PAINT ORANGE (3625 2275);
DISPLAY INVISIBLE (3625 2275);
FORCEADD CAP..1
(2550 950);
FORCEPROP 1 LASTPIN (2550 850) $PN 2
J 0
(2560 830);
DISPLAY 0.617021 (2560 830);
PAINT WHITE (2560 830);
FORCEPROP 1 LAST PART_NUMBER D97712-011
J 0
(2600 900);
DISPLAY 0.617021 (2600 900);
PAINT BLUE (2600 900);
FORCEPROP 1 LAST TOLERANCE 10%
J 0
(2600 950);
DISPLAY 0.617021 (2600 950);
PAINT SKYBLUE (2600 950);
FORCEPROP 1 LAST PACK_TYPE 0402
J 0
(2600 850);
DISPLAY 0.617021 (2600 850);
PAINT SKYBLUE (2600 850);
FORCEPROP 1 LAST MATERIAL X6S
J 0
(2725 950);
DISPLAY 0.617021 (2725 950);
PAINT SKYBLUE (2725 950);
FORCEPROP 1 LAST VALUE 1.0UF
J 0
(2600 1000);
DISPLAY 0.617021 (2600 1000);
PAINT SKYBLUE (2600 1000);
FORCEPROP 1 LAST VOLTAGE 16V
J 0
(2750 1000);
DISPLAY 0.617021 (2750 1000);
PAINT SKYBLUE (2750 1000);
FORCEPROP 1 LASTPIN (2550 1050) $PN 1
J 0
(2560 1030);
DISPLAY 0.617021 (2560 1030);
PAINT WHITE (2560 1030);
FORCEPROP 1 LAST LOCATION C4A9
J 0
(2600 1050);
DISPLAY 0.617021 (2600 1050);
PAINT AQUA (2600 1050);
FORCEPROP 2 LAST CDS_LIB mstr_discrete
J 0
(2550 950);
PAINT ORANGE (2550 950);
DISPLAY INVISIBLE (2550 950);
FORCEPROP 2 LAST SEC 1
J 0
(2606 1165);
DISPLAY 0.680851 (2606 1165);
PAINT MONO (2606 1165);
DISPLAY INVISIBLE (2606 1165);
FORCEPROP 2 LAST BOM_COST MEM_VRD_VTT_DEF
J 0
(2600 1150);
DISPLAY 1.021277 (2600 1150);
PAINT ORANGE (2600 1150);
DISPLAY INVISIBLE (2600 1150);
FORCEPROP 2 LAST SEC_TYPE 0402
J 0
(2606 1165);
DISPLAY 1.021277 (2606 1165);
PAINT ORANGE (2606 1165);
DISPLAY INVISIBLE (2606 1165);
FORCEPROP 2 LAST ROOM VTT_DEF_PWR_VR
J 0
(2600 1100);
DISPLAY 1.021277 (2600 1100);
PAINT ORANGE (2600 1100);
DISPLAY INVISIBLE (2600 1100);
FORCEPROP 1 LAST PATH I21
J 0
(2600 1100);
DISPLAY 0.978723 (2600 1100);
PAINT WHITE (2600 1100);
DISPLAY INVISIBLE (2600 1100);
FORCEPROP 2 LAST CDS_LOCATION C4A9
J 0
(2600 1050);
DISPLAY 0.617021 (2600 1050);
PAINT AQUA (2600 1050);
DISPLAY INVISIBLE (2600 1050);
FORCEADD GND..1
(2550 675);
FORCEPROP 3 LASTPIN (2550 725) SIG_NAME GND\g
J 0
(2560 735);
DISPLAY 0.659574 (2560 735);
PAINT MONO (2560 735);
DISPLAY INVISIBLE (2560 735);
FORCEPROP 1 LAST VOLTAGE 0.0V
J 0
(2505 632);
DISPLAY 0.340426 (2505 632);
PAINT SKYBLUE (2505 632);
DISPLAY INVISIBLE (2505 632);
FORCEPROP 2 LAST CDS_LIB mstr_symbols
J 0
(2550 675);
PAINT ORANGE (2550 675);
DISPLAY INVISIBLE (2550 675);
FORCEPROP 1 LAST BODY_TYPE PLUMBING
J 0
(2505 632);
DISPLAY 0.340426 (2505 632);
PAINT GREEN (2505 632);
DISPLAY INVISIBLE (2505 632);
FORCEPROP 1 LAST HDL_POWER GND
J 0
(2550 825);
DISPLAY 0.872340 (2550 825);
PAINT GREEN (2550 825);
DISPLAY INVISIBLE (2550 825);
FORCEPROP 1 LAST SIZE 1B
J 0
(2625 625);
DISPLAY 0.872340 (2625 625);
PAINT AQUA (2625 625);
DISPLAY INVISIBLE (2625 625);
FORCEPROP 1 LAST PATH I22
J 0
(2625 675);
DISPLAY 0.872340 (2625 675);
PAINT AQUA (2625 675);
DISPLAY INVISIBLE (2625 675);
FORCEADD GND..1
(2150 675);
FORCEPROP 3 LASTPIN (2150 725) SIG_NAME GND\g
J 0
(2160 735);
DISPLAY 0.659574 (2160 735);
PAINT MONO (2160 735);
DISPLAY INVISIBLE (2160 735);
FORCEPROP 1 LAST PATH I23
J 0
(2225 675);
DISPLAY 0.872340 (2225 675);
PAINT AQUA (2225 675);
DISPLAY INVISIBLE (2225 675);
FORCEPROP 1 LAST BODY_TYPE PLUMBING
J 0
(2105 632);
DISPLAY 0.340426 (2105 632);
PAINT GREEN (2105 632);
DISPLAY INVISIBLE (2105 632);
FORCEPROP 2 LAST CDS_LIB mstr_symbols
J 0
(2150 675);
PAINT ORANGE (2150 675);
DISPLAY INVISIBLE (2150 675);
FORCEPROP 1 LAST SIZE 1B
J 0
(2225 625);
DISPLAY 0.872340 (2225 625);
PAINT AQUA (2225 625);
DISPLAY INVISIBLE (2225 625);
FORCEPROP 1 LAST VOLTAGE 0.0V
J 0
(2105 632);
DISPLAY 0.340426 (2105 632);
PAINT SKYBLUE (2105 632);
DISPLAY INVISIBLE (2105 632);
FORCEPROP 1 LAST HDL_POWER GND
J 0
(2150 825);
DISPLAY 0.872340 (2150 825);
PAINT GREEN (2150 825);
DISPLAY INVISIBLE (2150 825);
FORCEADD CAP..1
(600 2475);
FORCEPROP 1 LAST VALUE 10UF
J 0
(650 2525);
DISPLAY 0.617021 (650 2525);
PAINT SKYBLUE (650 2525);
FORCEPROP 1 LAST TOLERANCE 20%
J 0
(650 2425);
DISPLAY 0.617021 (650 2425);
PAINT SKYBLUE (650 2425);
FORCEPROP 1 LAST VOLTAGE 4V
J 0
(650 2475);
DISPLAY 0.617021 (650 2475);
PAINT SKYBLUE (650 2475);
FORCEPROP 1 LAST MATERIAL X6S
J 0
(650 2375);
DISPLAY 0.617021 (650 2375);
PAINT SKYBLUE (650 2375);
FORCEPROP 1 LASTPIN (600 2375) $PN 2
J 0
(610 2355);
DISPLAY 0.617021 (610 2355);
PAINT WHITE (610 2355);
FORCEPROP 1 LAST PART_NUMBER E15431-001
J 0
(650 2325);
DISPLAY 0.617021 (650 2325);
PAINT BLUE (650 2325);
FORCEPROP 1 LAST PACK_TYPE 0603LF
J 0
(650 2275);
DISPLAY 0.617021 (650 2275);
PAINT SKYBLUE (650 2275);
FORCEPROP 1 LASTPIN (600 2575) $PN 1
J 0
(610 2555);
DISPLAY 0.617021 (610 2555);
PAINT WHITE (610 2555);
FORCEPROP 1 LAST LOCATION C6L3
J 0
(650 2575);
DISPLAY 0.617021 (650 2575);
PAINT AQUA (650 2575);
FORCEPROP 2 LAST CDS_LIB mstr_discrete
J 0
(600 2475);
PAINT ORANGE (600 2475);
DISPLAY INVISIBLE (600 2475);
FORCEPROP 2 LAST ROOM VTT_DEF_PWR_VR
J 0
(650 2625);
DISPLAY 1.021277 (650 2625);
PAINT ORANGE (650 2625);
DISPLAY INVISIBLE (650 2625);
FORCEPROP 1 LAST PATH I24
J 0
(650 2625);
DISPLAY 0.978723 (650 2625);
PAINT WHITE (650 2625);
DISPLAY INVISIBLE (650 2625);
FORCEPROP 2 LAST CDS_LOCATION C6L3
J 0
(650 2575);
DISPLAY 0.617021 (650 2575);
PAINT AQUA (650 2575);
DISPLAY INVISIBLE (650 2575);
FORCEPROP 2 LAST SEC 1
J 0
(656 2690);
DISPLAY 0.680851 (656 2690);
PAINT MONO (656 2690);
DISPLAY INVISIBLE (656 2690);
FORCEPROP 2 LAST BOM_COST MEM_VRD_VTT_DEF
J 0
(650 2675);
DISPLAY 1.021277 (650 2675);
PAINT ORANGE (650 2675);
DISPLAY INVISIBLE (650 2675);
FORCEPROP 2 LAST SEC_TYPE 0603LF
J 0
(656 2690);
DISPLAY 1.021277 (656 2690);
PAINT ORANGE (656 2690);
DISPLAY INVISIBLE (656 2690);
FORCEADD GND..1
(600 2200);
FORCEPROP 3 LASTPIN (600 2250) SIG_NAME GND\g
J 0
(610 2260);
DISPLAY 0.659574 (610 2260);
PAINT MONO (610 2260);
DISPLAY INVISIBLE (610 2260);
FORCEPROP 2 LAST ROOM VTT_DEF_PWR_VR
J 0
(95 2280);
DISPLAY 1.021277 (95 2280);
PAINT ORANGE (95 2280);
DISPLAY INVISIBLE (95 2280);
FORCEPROP 2 LAST BOM_COST MEM_VRD_VTT_DEF
J 0
(95 2330);
DISPLAY 1.021277 (95 2330);
PAINT ORANGE (95 2330);
DISPLAY INVISIBLE (95 2330);
FORCEPROP 1 LAST VOLTAGE 0.0V
J 0
(555 2157);
DISPLAY 0.340426 (555 2157);
PAINT SKYBLUE (555 2157);
DISPLAY INVISIBLE (555 2157);
FORCEPROP 2 LAST CDS_LIB mstr_symbols
J 0
(600 2200);
PAINT MONO (600 2200);
DISPLAY INVISIBLE (600 2200);
FORCEPROP 1 LAST SIZE 1B
J 0
(675 2150);
DISPLAY 0.893617 (675 2150);
PAINT GREEN (675 2150);
DISPLAY INVISIBLE (675 2150);
FORCEPROP 1 LAST BODY_TYPE PLUMBING
J 0
(555 2157);
DISPLAY 0.340426 (555 2157);
PAINT GREEN (555 2157);
DISPLAY INVISIBLE (555 2157);
FORCEPROP 1 LAST PATH I25
J 0
(675 2200);
DISPLAY 0.872340 (675 2200);
PAINT AQUA (675 2200);
DISPLAY INVISIBLE (675 2200);
FORCEPROP 1 LAST HDL_POWER GND
J 0
(600 2350);
DISPLAY 0.893617 (600 2350);
PAINT GREEN (600 2350);
DISPLAY INVISIBLE (600 2350);
FORCEADD CAP..1
(175 2450);
FORCEPROP 1 LASTPIN (175 2350) $PN 2
J 0
(185 2330);
DISPLAY 0.617021 (185 2330);
PAINT WHITE (185 2330);
FORCEPROP 1 LASTPIN (175 2550) $PN 1
J 0
(185 2530);
DISPLAY 0.617021 (185 2530);
PAINT WHITE (185 2530);
FORCEPROP 1 LAST VALUE 10UF
J 0
(225 2500);
DISPLAY 0.617021 (225 2500);
PAINT SKYBLUE (225 2500);
FORCEPROP 1 LAST TOLERANCE 20%
J 0
(225 2400);
DISPLAY 0.617021 (225 2400);
PAINT SKYBLUE (225 2400);
FORCEPROP 1 LAST PACK_TYPE 0603LF
J 0
(225 2250);
DISPLAY 0.617021 (225 2250);
PAINT SKYBLUE (225 2250);
FORCEPROP 1 LAST VOLTAGE 4V
J 0
(225 2450);
DISPLAY 0.617021 (225 2450);
PAINT SKYBLUE (225 2450);
FORCEPROP 1 LAST MATERIAL X6S
J 0
(225 2350);
DISPLAY 0.617021 (225 2350);
PAINT SKYBLUE (225 2350);
FORCEPROP 1 LAST LOCATION C6L4
J 0
(225 2550);
DISPLAY 0.617021 (225 2550);
PAINT AQUA (225 2550);
FORCEPROP 1 LAST PART_NUMBER E15431-001
J 0
(225 2300);
DISPLAY 0.617021 (225 2300);
PAINT BLUE (225 2300);
FORCEPROP 2 LAST CDS_LIB mstr_discrete
J 0
(175 2450);
PAINT ORANGE (175 2450);
DISPLAY INVISIBLE (175 2450);
FORCEPROP 2 LAST CDS_LOCATION C6L4
J 0
(225 2550);
DISPLAY 0.617021 (225 2550);
PAINT AQUA (225 2550);
DISPLAY INVISIBLE (225 2550);
FORCEPROP 2 LAST SEC_TYPE 0603LF
J 0
(231 2665);
DISPLAY 1.021277 (231 2665);
PAINT ORANGE (231 2665);
DISPLAY INVISIBLE (231 2665);
FORCEPROP 2 LAST BOM_COST MEM_VRD_VTT_DEF
J 0
(225 2650);
DISPLAY 1.021277 (225 2650);
PAINT ORANGE (225 2650);
DISPLAY INVISIBLE (225 2650);
FORCEPROP 2 LAST SEC 1
J 0
(231 2665);
DISPLAY 0.680851 (231 2665);
PAINT MONO (231 2665);
DISPLAY INVISIBLE (231 2665);
FORCEPROP 1 LAST PATH I26
J 0
(225 2600);
DISPLAY 0.978723 (225 2600);
PAINT WHITE (225 2600);
DISPLAY INVISIBLE (225 2600);
FORCEPROP 2 LAST ROOM VTT_DEF_PWR_VR
J 0
(225 2600);
DISPLAY 1.021277 (225 2600);
PAINT ORANGE (225 2600);
DISPLAY INVISIBLE (225 2600);
FORCEADD GND..1
(175 2200);
FORCEPROP 3 LASTPIN (175 2250) SIG_NAME GND\g
J 0
(185 2260);
DISPLAY 0.659574 (185 2260);
PAINT MONO (185 2260);
DISPLAY INVISIBLE (185 2260);
FORCEPROP 2 LAST BOM_COST MEM_VRD_VTT_DEF
J 0
(-330 2330);
DISPLAY 1.021277 (-330 2330);
PAINT ORANGE (-330 2330);
DISPLAY INVISIBLE (-330 2330);
FORCEPROP 2 LAST ROOM VTT_DEF_PWR_VR
J 0
(-330 2280);
DISPLAY 1.021277 (-330 2280);
PAINT ORANGE (-330 2280);
DISPLAY INVISIBLE (-330 2280);
FORCEPROP 1 LAST VOLTAGE 0.0V
J 0
(130 2157);
DISPLAY 0.340426 (130 2157);
PAINT SKYBLUE (130 2157);
DISPLAY INVISIBLE (130 2157);
FORCEPROP 1 LAST SIZE 1B
J 0
(250 2150);
DISPLAY 0.893617 (250 2150);
PAINT GREEN (250 2150);
DISPLAY INVISIBLE (250 2150);
FORCEPROP 2 LAST CDS_LIB mstr_symbols
J 0
(175 2200);
DISPLAY 0.744681 (175 2200);
PAINT MONO (175 2200);
DISPLAY INVISIBLE (175 2200);
FORCEPROP 1 LAST BODY_TYPE PLUMBING
J 0
(130 2157);
DISPLAY 0.340426 (130 2157);
PAINT GREEN (130 2157);
DISPLAY INVISIBLE (130 2157);
FORCEPROP 1 LAST PATH I27
J 0
(250 2200);
DISPLAY 0.872340 (250 2200);
PAINT AQUA (250 2200);
DISPLAY INVISIBLE (250 2200);
FORCEPROP 1 LAST HDL_POWER GND
J 0
(175 2350);
DISPLAY 0.893617 (175 2350);
PAINT GREEN (175 2350);
DISPLAY INVISIBLE (175 2350);
FORCEADD CAP..1
(600 1600);
FORCEPROP 1 LASTPIN (600 1500) $PN 2
J 0
(610 1480);
DISPLAY 0.617021 (610 1480);
PAINT WHITE (610 1480);
FORCEPROP 1 LAST PACK_TYPE 0402
J 0
(650 1500);
DISPLAY 0.617021 (650 1500);
PAINT SKYBLUE (650 1500);
FORCEPROP 1 LAST TOLERANCE 10%
J 0
(650 1600);
DISPLAY 0.617021 (650 1600);
PAINT SKYBLUE (650 1600);
FORCEPROP 1 LASTPIN (600 1700) $PN 1
J 0
(610 1680);
DISPLAY 0.617021 (610 1680);
PAINT WHITE (610 1680);
FORCEPROP 1 LAST VALUE 1.0UF
J 0
(650 1650);
DISPLAY 0.617021 (650 1650);
PAINT SKYBLUE (650 1650);
FORCEPROP 1 LAST PART_NUMBER D97712-011
J 0
(650 1550);
DISPLAY 0.617021 (650 1550);
PAINT BLUE (650 1550);
FORCEPROP 1 LAST LOCATION C4A10
J 0
(650 1700);
DISPLAY 0.617021 (650 1700);
PAINT AQUA (650 1700);
FORCEPROP 1 LAST MATERIAL X6S
J 0
(775 1600);
DISPLAY 0.617021 (775 1600);
PAINT SKYBLUE (775 1600);
FORCEPROP 1 LAST VOLTAGE 16V
J 0
(800 1650);
DISPLAY 0.617021 (800 1650);
PAINT SKYBLUE (800 1650);
FORCEPROP 1 LAST PATH I28
J 0
(650 1750);
DISPLAY 0.978723 (650 1750);
PAINT WHITE (650 1750);
DISPLAY INVISIBLE (650 1750);
FORCEPROP 2 LAST CDS_LOCATION C4A10
J 0
(650 1700);
DISPLAY 0.617021 (650 1700);
PAINT AQUA (650 1700);
DISPLAY INVISIBLE (650 1700);
FORCEPROP 2 LAST CDS_LIB mstr_discrete
J 0
(600 1600);
PAINT ORANGE (600 1600);
DISPLAY INVISIBLE (600 1600);
FORCEPROP 2 LAST ROOM VTT_DEF_PWR_VR
J 0
(650 1750);
DISPLAY 1.021277 (650 1750);
PAINT ORANGE (650 1750);
DISPLAY INVISIBLE (650 1750);
FORCEPROP 2 LAST BOM_COST MEM_VRD_VTT_DEF
J 0
(650 1800);
DISPLAY 1.021277 (650 1800);
PAINT ORANGE (650 1800);
DISPLAY INVISIBLE (650 1800);
FORCEPROP 2 LAST SEC_TYPE 0402
J 0
(650 1796);
DISPLAY 1.021277 (650 1796);
PAINT ORANGE (650 1796);
DISPLAY INVISIBLE (650 1796);
FORCEPROP 2 LAST SEC 1
J 0
(650 1796);
DISPLAY 0.680851 (650 1796);
PAINT MONO (650 1796);
DISPLAY INVISIBLE (650 1796);
FORCEADD GND..1
(600 1350);
FORCEPROP 3 LASTPIN (600 1400) SIG_NAME GND\g
J 0
(610 1410);
DISPLAY 0.659574 (610 1410);
PAINT MONO (610 1410);
DISPLAY INVISIBLE (610 1410);
FORCEPROP 1 LAST BODY_TYPE PLUMBING
J 0
(555 1307);
DISPLAY 0.340426 (555 1307);
PAINT GREEN (555 1307);
DISPLAY INVISIBLE (555 1307);
FORCEPROP 2 LAST CDS_LIB mstr_symbols
J 0
(600 1350);
DISPLAY 0.744681 (600 1350);
PAINT MONO (600 1350);
DISPLAY INVISIBLE (600 1350);
FORCEPROP 1 LAST VOLTAGE 0.0V
J 0
(555 1307);
DISPLAY 0.340426 (555 1307);
PAINT SKYBLUE (555 1307);
DISPLAY INVISIBLE (555 1307);
FORCEPROP 1 LAST PATH I29
J 0
(675 1350);
DISPLAY 0.872340 (675 1350);
PAINT AQUA (675 1350);
DISPLAY INVISIBLE (675 1350);
FORCEPROP 1 LAST SIZE 1B
J 0
(675 1300);
DISPLAY 0.893617 (675 1300);
PAINT GREEN (675 1300);
DISPLAY INVISIBLE (675 1300);
FORCEPROP 1 LAST HDL_POWER GND
J 0
(600 1500);
DISPLAY 0.893617 (600 1500);
PAINT GREEN (600 1500);
DISPLAY INVISIBLE (600 1500);
FORCEADD RES..1
(275 1850);
FORCEPROP 1 LAST VALUE 0.0
J 2
(250 1750);
DISPLAY 0.617021 (250 1750);
PAINT SKYBLUE (250 1750);
FORCEPROP 1 LAST WATTAGE 1/16W
J 2
(250 1700);
DISPLAY 0.617021 (250 1700);
PAINT SKYBLUE (250 1700);
FORCEPROP 1 LASTPIN (175 1850) $PN 1
J 0
(187 1862);
DISPLAY 0.617021 (187 1862);
PAINT WHITE (187 1862);
FORCEPROP 1 LAST PART_NUMBER G21497-005
J 0
(150 1800);
DISPLAY 0.617021 (150 1800);
PAINT BLUE (150 1800);
FORCEPROP 1 LAST LOCATION R6L11
J 0
(225 1900);
DISPLAY 0.617021 (225 1900);
PAINT AQUA (225 1900);
FORCEPROP 1 LAST PACK_TYPE 0402
J 0
(200 1650);
DISPLAY 0.617021 (200 1650);
PAINT SKYBLUE (200 1650);
FORCEPROP 1 LAST TOLERANCE 5%
J 0
(275 1750);
DISPLAY 0.617021 (275 1750);
PAINT SKYBLUE (275 1750);
FORCEPROP 1 LAST MATERIAL CHIP
J 0
(275 1700);
DISPLAY 0.617021 (275 1700);
PAINT SKYBLUE (275 1700);
FORCEPROP 1 LASTPIN (375 1850) $PN 2
J 0
(337 1862);
DISPLAY 0.617021 (337 1862);
PAINT WHITE (337 1862);
FORCEPROP 1 LAST PATH I30
J 0
(225 2000);
DISPLAY 0.978723 (225 2000);
PAINT WHITE (225 2000);
DISPLAY INVISIBLE (225 2000);
FORCEPROP 2 LAST ROOM VTT_DEF_PWR_VR
J 0
(235 1935);
DISPLAY 1.021277 (235 1935);
PAINT ORANGE (235 1935);
DISPLAY INVISIBLE (235 1935);
FORCEPROP 2 LAST BOM_COST MEM_VRD_VTT_DEF
J 0
(235 1985);
DISPLAY 1.021277 (235 1985);
PAINT ORANGE (235 1985);
DISPLAY INVISIBLE (235 1985);
FORCEPROP 2 LAST CDS_LOCATION R6L11
J 0
(225 1900);
DISPLAY 0.617021 (225 1900);
PAINT AQUA (225 1900);
DISPLAY INVISIBLE (225 1900);
FORCEPROP 2 LAST CDS_LIB mstr_discrete
J 0
(275 1850);
DISPLAY 0.744681 (275 1850);
PAINT MONO (275 1850);
DISPLAY INVISIBLE (275 1850);
FORCEPROP 2 LAST SEC_TYPE 0402
J 0
(241 2050);
DISPLAY 1.021277 (241 2050);
PAINT ORANGE (241 2050);
DISPLAY INVISIBLE (241 2050);
FORCEPROP 2 LAST SEC 1
J 0
(241 2050);
DISPLAY 0.680851 (241 2050);
PAINT MONO (241 2050);
DISPLAY INVISIBLE (241 2050);
FORCEADD MIC5166..1
(1700 1150);
FORCEPROP 2 LASTPIN (1400 900) $PN 2
J 2
(1390 910);
DISPLAY 0.617021 (1390 910);
PAINT ORANGE (1390 910);
FORCEPROP 1 LAST PART_NUMBER H55101-001
J 0
(1450 750);
DISPLAY 0.617021 (1450 750);
PAINT BLUE (1450 750);
FORCEPROP 2 LASTPIN (2000 950) $PN 3
J 0
(2010 960);
DISPLAY 0.617021 (2010 960);
PAINT ORANGE (2010 960);
FORCEPROP 2 LASTPIN (2000 1000) $PN 8
J 0
(2010 1010);
DISPLAY 0.617021 (2010 1010);
PAINT ORANGE (2010 1010);
FORCEPROP 2 LASTPIN (1400 1150) $PN 7
J 2
(1390 1160);
DISPLAY 0.617021 (1390 1160);
PAINT ORANGE (1390 1160);
FORCEPROP 2 LASTPIN (1400 1050) $PN 6
J 2
(1390 1060);
DISPLAY 0.617021 (1390 1060);
PAINT ORANGE (1390 1060);
FORCEPROP 2 LASTPIN (1400 1250) $PN 4
J 2
(1390 1260);
DISPLAY 0.617021 (1390 1260);
PAINT ORANGE (1390 1260);
FORCEPROP 2 LASTPIN (1400 1400) $PN 10
J 2
(1390 1410);
DISPLAY 0.617021 (1390 1410);
PAINT ORANGE (1390 1410);
FORCEPROP 1 LAST MATERIAL IC
J 0
(1450 1525);
DISPLAY 0.617021 (1450 1525);
PAINT SKYBLUE (1450 1525);
FORCEPROP 1 LAST LOCATION EU4A1
J 0
(1450 1575);
DISPLAY 0.617021 (1450 1575);
PAINT AQUA (1450 1575);
FORCEPROP 2 LASTPIN (2000 1400) $PN 9
J 0
(2010 1410);
DISPLAY 0.617021 (2010 1410);
PAINT ORANGE (2010 1410);
FORCEPROP 2 LASTPIN (2000 1300) $PN 1
J 0
(2010 1310);
DISPLAY 0.617021 (2010 1310);
PAINT ORANGE (2010 1310);
FORCEPROP 2 LASTPIN (2000 1100) $PN 5
J 0
(2010 1110);
DISPLAY 0.617021 (2010 1110);
PAINT ORANGE (2010 1110);
FORCEPROP 2 LASTPIN (2000 850) $PN 11
J 0
(2010 860);
DISPLAY 0.617021 (2010 860);
PAINT ORANGE (2010 860);
FORCEPROP 2 LAST BOM_COST MEM_VRD_VTT_DEF
J 0
(1450 1670);
DISPLAY 1.021277 (1450 1670);
PAINT ORANGE (1450 1670);
DISPLAY INVISIBLE (1450 1670);
FORCEPROP 1 LAST PACK_TYPE DFN
J 0
(1450 1625);
PAINT SKYBLUE (1450 1625);
DISPLAY INVISIBLE (1450 1625);
FORCEPROP 2 LAST SEC_TYPE DFN
J 0
(1458 1622);
DISPLAY 1.021277 (1458 1622);
PAINT ORANGE (1458 1622);
DISPLAY INVISIBLE (1458 1622);
FORCEPROP 2 LAST SEC 1
J 0
(1458 1622);
DISPLAY 0.680851 (1458 1622);
PAINT MONO (1458 1622);
DISPLAY INVISIBLE (1458 1622);
FORCEPROP 2 LAST CDS_LOCATION EU4A1
J 0
(1450 1575);
DISPLAY 0.617021 (1450 1575);
PAINT AQUA (1450 1575);
DISPLAY INVISIBLE (1450 1575);
FORCEPROP 2 LAST ROOM VTT_DEF_PWR_VR
J 0
(1450 1622);
DISPLAY 1.021277 (1450 1622);
PAINT ORANGE (1450 1622);
DISPLAY INVISIBLE (1450 1622);
FORCEPROP 1 LAST CDS_LMAN_SYM_OUTLINE -250,350,250,-350
J 0
(1700 1150);
DISPLAY 0.468085 (1700 1150);
PAINT GREEN (1700 1150);
DISPLAY INVISIBLE (1700 1150);
FORCEPROP 2 LAST CDS_LIB mstr_vreg
J 0
(1700 1150);
PAINT ORANGE (1700 1150);
DISPLAY INVISIBLE (1700 1150);
FORCEPROP 1 LAST PATH I31
J 0
(1900 1525);
PAINT GREEN (1900 1525);
DISPLAY INVISIBLE (1900 1525);
FORCEADD RES..2
R 1
(-575 1650);
FORCEPROP 1 LAST TOLERANCE 5%
J 0
(-725 1595);
DISPLAY 0.617021 (-725 1595);
PAINT SKYBLUE (-725 1595);
FORCEPROP 1 LAST VALUE 0.0
J 0
(-650 1595);
DISPLAY 0.617021 (-650 1595);
PAINT SKYBLUE (-650 1595);
FORCEPROP 1 LASTPIN (-675 1650) $PN 1
R 1
J 0
(-637 1655);
DISPLAY 0.617021 (-637 1655);
PAINT WHITE (-637 1655);
FORCEPROP 1 LAST LOCATION R6L10
J 0
(-600 1695);
DISPLAY 0.617021 (-600 1695);
PAINT AQUA (-600 1695);
FORCEPROP 1 LAST PART_NUMBER G21497-005
J 0
(-675 1540);
DISPLAY 0.617021 (-675 1540);
PAINT BLUE (-675 1540);
FORCEPROP 1 LAST WATTAGE 1/16W
J 0
(-550 1590);
DISPLAY 0.617021 (-550 1590);
PAINT SKYBLUE (-550 1590);
FORCEPROP 1 LASTPIN (-475 1650) $PN 2
R 1
J 0
(-485 1655);
DISPLAY 0.617021 (-485 1655);
PAINT WHITE (-485 1655);
FORCEPROP 1 LAST PACK_TYPE 0402
J 0
(-350 1590);
DISPLAY 0.617021 (-350 1590);
PAINT SKYBLUE (-350 1590);
FORCEPROP 1 LAST MATERIAL CHIP
J 0
(-650 1415);
PAINT SKYBLUE (-650 1415);
DISPLAY INVISIBLE (-650 1415);
FORCEPROP 1 LAST PATH I34
R 1
J 0
(-750 1700);
DISPLAY 0.978723 (-750 1700);
PAINT WHITE (-750 1700);
DISPLAY INVISIBLE (-750 1700);
FORCEPROP 2 LAST CDS_LIB mstr_discrete
R 1
J 0
(-575 1650);
PAINT ORANGE (-575 1650);
DISPLAY INVISIBLE (-575 1650);
FORCEPROP 2 LAST CDS_LOCATION R6L10
J 0
(-600 1695);
DISPLAY 0.617021 (-600 1695);
PAINT AQUA (-600 1695);
DISPLAY INVISIBLE (-600 1695);
FORCEPROP 2 LAST SEC_TYPE 0402
J 0
(-594 1740);
DISPLAY 1.021277 (-594 1740);
PAINT ORANGE (-594 1740);
DISPLAY INVISIBLE (-594 1740);
FORCEPROP 2 LAST NO_XNET_CONNECTION 1
J 0
(-600 1725);
PAINT MONO (-600 1725);
DISPLAY INVISIBLE (-600 1725);
FORCEPROP 2 LAST SEC 1
J 0
(-594 1740);
DISPLAY 0.680851 (-594 1740);
PAINT MONO (-594 1740);
DISPLAY INVISIBLE (-594 1740);
FORCEPROP 2 LAST ROOM VTT_DEF_PWR_VR
J 0
(-600 1750);
DISPLAY 1.021277 (-600 1750);
PAINT ORANGE (-600 1750);
DISPLAY INVISIBLE (-600 1750);
FORCEPROP 2 LAST BOM_COST MEM_VRD_VTT_DEF
J 0
(-600 1800);
DISPLAY 1.021277 (-600 1800);
PAINT ORANGE (-600 1800);
DISPLAY INVISIBLE (-600 1800);
FORCEADD PVDDQ_DEF..1
(-1300 2875);
FORCEPROP 3 LASTPIN (-1300 2825) SIG_NAME PVDDQ_DEF\g
J 0
(-1290 2835);
DISPLAY 0.659574 (-1290 2835);
PAINT MONO (-1290 2835);
DISPLAY INVISIBLE (-1290 2835);
FORCEPROP 1 LAST VOLTAGE 1.2V
J 0
(-1345 2832);
DISPLAY 0.340426 (-1345 2832);
PAINT SKYBLUE (-1345 2832);
DISPLAY INVISIBLE (-1345 2832);
FORCEPROP 2 LAST CDS_LIB mstr_symbols
J 0
(-1300 2875);
PAINT ORANGE (-1300 2875);
DISPLAY INVISIBLE (-1300 2875);
FORCEPROP 1 LAST BODY_TYPE PLUMBING
J 0
(-1345 2832);
DISPLAY 0.340426 (-1345 2832);
PAINT GREEN (-1345 2832);
DISPLAY INVISIBLE (-1345 2832);
FORCEPROP 1 LAST PATH I35
J 0
(-1250 2900);
DISPLAY 0.872340 (-1250 2900);
PAINT AQUA (-1250 2900);
DISPLAY INVISIBLE (-1250 2900);
FORCEPROP 1 LAST HDL_POWER PVDDQ_DEF
J 1
(-1300 2925);
DISPLAY 0.872340 (-1300 2925);
PAINT GREEN (-1300 2925);
DISPLAY INVISIBLE (-1300 2925);
FORCEADD RES..2
R 2
(-175 750);
FORCEPROP 1 LAST MATERIAL EMPTY
J 2
(-215 675);
DISPLAY 0.617021 (-215 675);
PAINT RED (-215 675);
FORCEPROP 1 LAST LOCATION R6L4
J 2
(-220 875);
DISPLAY 0.617021 (-220 875);
PAINT AQUA (-220 875);
FORCEPROP 1 LAST PART_NUMBER G21796-021
J 2
(-215 625);
DISPLAY 0.617021 (-215 625);
PAINT BLUE (-215 625);
FORCEPROP 1 LAST VALUE 1.0M
J 2
(-220 825);
DISPLAY 0.617021 (-220 825);
PAINT SKYBLUE (-220 825);
FORCEPROP 1 LAST TOLERANCE 1%
J 2
(-220 775);
DISPLAY 0.617021 (-220 775);
PAINT SKYBLUE (-220 775);
FORCEPROP 1 LAST PACK_TYPE 0402
J 2
(-215 575);
DISPLAY 0.617021 (-215 575);
PAINT SKYBLUE (-215 575);
FORCEPROP 1 LAST WATTAGE 1/16W
J 2
(-215 725);
DISPLAY 0.617021 (-215 725);
PAINT SKYBLUE (-215 725);
FORCEPROP 1 LASTPIN (-175 650) $PN 2
J 2
(-180 660);
DISPLAY 0.617021 (-180 660);
PAINT WHITE (-180 660);
FORCEPROP 1 LASTPIN (-175 850) $PN 1
J 2
(-180 812);
DISPLAY 0.617021 (-180 812);
PAINT WHITE (-180 812);
FORCEPROP 2 LAST CDS_LIB mstr_discrete
J 0
(-175 750);
PAINT ORANGE (-175 750);
DISPLAY INVISIBLE (-175 750);
FORCEPROP 2 LAST CDS_LOCATION R6L4
J 2
(-220 875);
DISPLAY 0.617021 (-220 875);
PAINT AQUA (-220 875);
DISPLAY INVISIBLE (-220 875);
FORCEPROP 2 LAST BOM_COST MEM_VRD_VTT_DEF
J 0
(-210 965);
DISPLAY 1.021277 (-210 965);
PAINT ORANGE (-210 965);
DISPLAY INVISIBLE (-210 965);
FORCEPROP 2 LAST SEC_TYPE 0402
J 0
(-204 980);
DISPLAY 1.021277 (-204 980);
PAINT ORANGE (-204 980);
DISPLAY INVISIBLE (-204 980);
FORCEPROP 2 LAST SEC 1
J 0
(-204 980);
DISPLAY 0.680851 (-204 980);
PAINT MONO (-204 980);
DISPLAY INVISIBLE (-204 980);
FORCEPROP 1 LAST PATH I37
J 2
(-225 925);
DISPLAY 0.978723 (-225 925);
PAINT WHITE (-225 925);
DISPLAY INVISIBLE (-225 925);
FORCEPROP 2 LAST ROOM VTT_DEF_PWR_VR
J 0
(-210 915);
DISPLAY 1.021277 (-210 915);
PAINT ORANGE (-210 915);
DISPLAY INVISIBLE (-210 915);
FORCEADD RES..1
(-375 225);
FORCEPROP 1 LAST MATERIAL CHIP
J 0
(-675 50);
DISPLAY 0.617021 (-675 50);
PAINT SKYBLUE (-675 50);
FORCEPROP 1 LAST WATTAGE 1/16W
J 2
(-525 125);
DISPLAY 0.617021 (-525 125);
PAINT SKYBLUE (-525 125);
FORCEPROP 1 LAST PART_NUMBER G21497-005
J 0
(-532 169);
DISPLAY 0.617021 (-532 169);
PAINT BLUE (-532 169);
FORCEPROP 1 LAST VALUE 0.0
J 2
(-400 125);
DISPLAY 0.617021 (-400 125);
PAINT SKYBLUE (-400 125);
FORCEPROP 1 LAST PACK_TYPE 0402
J 0
(-450 50);
DISPLAY 0.617021 (-450 50);
PAINT SKYBLUE (-450 50);
FORCEPROP 1 LAST TOLERANCE 5%
J 0
(-375 125);
DISPLAY 0.617021 (-375 125);
PAINT SKYBLUE (-375 125);
FORCEPROP 1 LASTPIN (-475 225) $PN 1
J 0
(-463 237);
DISPLAY 0.617021 (-463 237);
PAINT WHITE (-463 237);
FORCEPROP 1 LASTPIN (-275 225) $PN 2
J 0
(-313 237);
DISPLAY 0.617021 (-313 237);
PAINT WHITE (-313 237);
FORCEPROP 1 LAST LOCATION R4A2
J 0
(-425 275);
DISPLAY 0.617021 (-425 275);
PAINT AQUA (-425 275);
FORCEPROP 2 LAST CDS_LIB mstr_discrete
J 0
(-375 225);
PAINT ORANGE (-375 225);
DISPLAY INVISIBLE (-375 225);
FORCEPROP 2 LAST SEC 1
J 0
(-425 425);
DISPLAY 0.680851 (-425 425);
PAINT MONO (-425 425);
DISPLAY INVISIBLE (-425 425);
FORCEPROP 2 LAST CDS_LOCATION R4A2
J 0
(-425 275);
DISPLAY 0.617021 (-425 275);
PAINT AQUA (-425 275);
DISPLAY INVISIBLE (-425 275);
FORCEPROP 2 LAST ROOM VTT_DEF_PWR_VR
J 0
(-405 380);
DISPLAY 1.021277 (-405 380);
PAINT ORANGE (-405 380);
DISPLAY INVISIBLE (-405 380);
FORCEPROP 2 LAST BOM_COST MEM_VRD_VTT_DEF
J 0
(-405 430);
DISPLAY 1.021277 (-405 430);
PAINT ORANGE (-405 430);
DISPLAY INVISIBLE (-405 430);
FORCEPROP 1 LAST PATH I38
J 0
(-425 375);
DISPLAY 0.978723 (-425 375);
PAINT WHITE (-425 375);
DISPLAY INVISIBLE (-425 375);
FORCEPROP 2 LAST SEC_TYPE 0402
J 0
(-425 425);
DISPLAY 1.021277 (-425 425);
PAINT ORANGE (-425 425);
DISPLAY INVISIBLE (-425 425);
FORCEADD GND..1
(-225 -525);
FORCEPROP 3 LASTPIN (-225 -475) SIG_NAME GND\g
J 0
(-215 -465);
DISPLAY 0.659574 (-215 -465);
PAINT MONO (-215 -465);
DISPLAY INVISIBLE (-215 -465);
FORCEPROP 1 LAST VOLTAGE 0.0V
J 0
(-270 -568);
DISPLAY 0.340426 (-270 -568);
PAINT SKYBLUE (-270 -568);
DISPLAY INVISIBLE (-270 -568);
FORCEPROP 1 LAST SIZE 1B
J 0
(-150 -575);
DISPLAY 0.893617 (-150 -575);
PAINT GREEN (-150 -575);
DISPLAY INVISIBLE (-150 -575);
FORCEPROP 1 LAST BODY_TYPE PLUMBING
J 0
(-270 -568);
DISPLAY 0.340426 (-270 -568);
PAINT GREEN (-270 -568);
DISPLAY INVISIBLE (-270 -568);
FORCEPROP 2 LAST CDS_LIB mstr_symbols
J 0
(-225 -525);
PAINT MONO (-225 -525);
DISPLAY INVISIBLE (-225 -525);
FORCEPROP 1 LAST PATH I39
J 0
(-150 -525);
DISPLAY 0.872340 (-150 -525);
PAINT AQUA (-150 -525);
DISPLAY INVISIBLE (-150 -525);
FORCEPROP 1 LAST HDL_POWER GND
J 0
(-225 -375);
DISPLAY 0.893617 (-225 -375);
PAINT GREEN (-225 -375);
DISPLAY INVISIBLE (-225 -375);
FORCEADD CAP..1
R 2
(-225 -300);
FORCEPROP 1 LAST MATERIAL EMPTY
J 2
(-266 -444);
DISPLAY 0.617021 (-266 -444);
PAINT RED (-266 -444);
FORCEPROP 1 LAST PACK_TYPE 0402LF
J 2
(-275 -393);
DISPLAY 0.617021 (-275 -393);
PAINT SKYBLUE (-275 -393);
FORCEPROP 1 LAST TOLERANCE 10%
J 2
(-275 -350);
DISPLAY 0.617021 (-275 -350);
PAINT SKYBLUE (-275 -350);
FORCEPROP 1 LAST VOLTAGE 50V
J 2
(-275 -300);
DISPLAY 0.617021 (-275 -300);
PAINT SKYBLUE (-275 -300);
FORCEPROP 1 LAST LOCATION C4A2
J 2
(-275 -200);
DISPLAY 0.617021 (-275 -200);
PAINT AQUA (-275 -200);
FORCEPROP 1 LAST VALUE 1000PF
J 2
(-275 -250);
DISPLAY 0.617021 (-275 -250);
PAINT SKYBLUE (-275 -250);
FORCEPROP 1 LASTPIN (-225 -400) $PN 2
J 2
(-235 -420);
DISPLAY 0.617021 (-235 -420);
PAINT WHITE (-235 -420);
FORCEPROP 1 LASTPIN (-225 -200) $PN 1
J 2
(-235 -220);
DISPLAY 0.617021 (-235 -220);
PAINT WHITE (-235 -220);
FORCEPROP 1 LAST PART_NUMBER A36096-046
J 2
(-275 -450);
DISPLAY 0.659574 (-275 -450);
PAINT BLUE (-275 -450);
DISPLAY INVISIBLE (-275 -450);
FORCEPROP 2 LAST BOM_COST MEM_VRD_VTT_DEF
J 0
(-260 -95);
DISPLAY 1.021277 (-260 -95);
PAINT ORANGE (-260 -95);
DISPLAY INVISIBLE (-260 -95);
FORCEPROP 2 LAST CDS_LOCATION C4A2
J 2
(-275 -200);
DISPLAY 0.617021 (-275 -200);
PAINT AQUA (-275 -200);
DISPLAY INVISIBLE (-275 -200);
FORCEPROP 1 LAST PATH I40
J 2
(-275 -150);
DISPLAY 0.978723 (-275 -150);
PAINT WHITE (-275 -150);
DISPLAY INVISIBLE (-275 -150);
FORCEPROP 2 LAST ROOM VTT_DEF_PWR_VR
J 0
(-260 -145);
DISPLAY 1.021277 (-260 -145);
PAINT ORANGE (-260 -145);
DISPLAY INVISIBLE (-260 -145);
FORCEPROP 2 LAST CDS_LIB mstr_discrete
J 0
(-225 -300);
PAINT ORANGE (-225 -300);
DISPLAY INVISIBLE (-225 -300);
FORCEPROP 2 LAST SEC_TYPE 0402LF
J 0
(-254 -80);
DISPLAY 1.021277 (-254 -80);
PAINT ORANGE (-254 -80);
DISPLAY INVISIBLE (-254 -80);
FORCEPROP 2 LAST SEC 1
J 0
(-254 -80);
DISPLAY 0.680851 (-254 -80);
PAINT MONO (-254 -80);
DISPLAY INVISIBLE (-254 -80);
FORCEADD OFFPAGE..1
(-1275 225);
FORCEPROP 2 LAST $XR0 218 
J 0
(-1527 225);
DISPLAY 0.638298 (-1527 225);
PAINT MONO (-1527 225);
FORCEPROP 2 LAST PATH I41
J 0
(-1536 267);
DISPLAY 1.021277 (-1536 267);
PAINT ORANGE (-1536 267);
DISPLAY INVISIBLE (-1536 267);
FORCEPROP 1 LAST COMMENT_BODY TRUE
J 0
(-1150 125);
DISPLAY 0.872340 (-1150 125);
PAINT GREEN (-1150 125);
DISPLAY INVISIBLE (-1150 125);
FORCEPROP 2 LAST CDS_LIB mstr_standard
J 0
(-1275 225);
DISPLAY 0.744681 (-1275 225);
PAINT MONO (-1275 225);
DISPLAY INVISIBLE (-1275 225);
FORCEPROP 1 LAST OFFPAGE TRUE
J 0
(-950 100);
DISPLAY 0.872340 (-950 100);
PAINT GREEN (-950 100);
DISPLAY INVISIBLE (-950 100);
FORCEADD P3V3..1
(-450 2250);
FORCEPROP 3 LASTPIN (-450 2200) SIG_NAME P3V3\g
J 0
(-440 2210);
DISPLAY 0.659574 (-440 2210);
PAINT MONO (-440 2210);
DISPLAY INVISIBLE (-440 2210);
FORCEPROP 1 LAST HDL_POWER P3V3
J 0
(-775 2125);
DISPLAY 0.872340 (-775 2125);
PAINT ORANGE (-775 2125);
DISPLAY INVISIBLE (-775 2125);
FORCEPROP 1 LAST VOLTAGE 3.3V
J 0
(-495 2207);
DISPLAY 0.340426 (-495 2207);
PAINT SKYBLUE (-495 2207);
DISPLAY INVISIBLE (-495 2207);
FORCEPROP 1 LAST SIZE 1B
J 0
(-405 2272);
DISPLAY 0.340426 (-405 2272);
PAINT GREEN (-405 2272);
DISPLAY INVISIBLE (-405 2272);
FORCEPROP 2 LAST CDS_LIB mstr_symbols
J 0
(-450 2250);
PAINT ORANGE (-450 2250);
DISPLAY INVISIBLE (-450 2250);
FORCEPROP 1 LAST PATH I42
J 0
(-405 2252);
DISPLAY 0.340426 (-405 2252);
PAINT GREEN (-405 2252);
DISPLAY INVISIBLE (-405 2252);
FORCEPROP 1 LAST BODY_TYPE PLUMBING
J 0
(-495 2207);
DISPLAY 0.340426 (-495 2207);
PAINT GREEN (-495 2207);
DISPLAY INVISIBLE (-495 2207);
FORCEADD P3V3..1
(3575 2425);
FORCEPROP 3 LASTPIN (3575 2375) SIG_NAME P3V3\g
J 0
(3585 2385);
DISPLAY 0.659574 (3585 2385);
PAINT MONO (3585 2385);
DISPLAY INVISIBLE (3585 2385);
FORCEPROP 1 LAST HDL_POWER P3V3
J 0
(3250 2300);
DISPLAY 0.872340 (3250 2300);
PAINT ORANGE (3250 2300);
DISPLAY INVISIBLE (3250 2300);
FORCEPROP 1 LAST BODY_TYPE PLUMBING
J 0
(3530 2382);
DISPLAY 0.340426 (3530 2382);
PAINT GREEN (3530 2382);
DISPLAY INVISIBLE (3530 2382);
FORCEPROP 2 LAST CDS_LIB mstr_symbols
J 0
(3575 2425);
PAINT ORANGE (3575 2425);
DISPLAY INVISIBLE (3575 2425);
FORCEPROP 1 LAST VOLTAGE 3.3V
J 0
(3530 2382);
DISPLAY 0.340426 (3530 2382);
PAINT SKYBLUE (3530 2382);
DISPLAY INVISIBLE (3530 2382);
FORCEPROP 1 LAST SIZE 1B
J 0
(3620 2447);
DISPLAY 0.340426 (3620 2447);
PAINT GREEN (3620 2447);
DISPLAY INVISIBLE (3620 2447);
FORCEPROP 1 LAST PATH I43
J 0
(3620 2427);
DISPLAY 0.340426 (3620 2427);
PAINT GREEN (3620 2427);
DISPLAY INVISIBLE (3620 2427);
FORCEADD GND..1
(425 875);
FORCEPROP 3 LASTPIN (425 925) SIG_NAME GND\g
J 0
(435 935);
DISPLAY 0.659574 (435 935);
PAINT MONO (435 935);
DISPLAY INVISIBLE (435 935);
FORCEPROP 1 LAST BODY_TYPE PLUMBING
J 0
(380 832);
DISPLAY 0.340426 (380 832);
PAINT GREEN (380 832);
DISPLAY INVISIBLE (380 832);
FORCEPROP 1 LAST VOLTAGE 0.0V
J 0
(380 832);
DISPLAY 0.340426 (380 832);
PAINT SKYBLUE (380 832);
DISPLAY INVISIBLE (380 832);
FORCEPROP 1 LAST PATH I45
J 0
(500 875);
DISPLAY 0.872340 (500 875);
PAINT AQUA (500 875);
DISPLAY INVISIBLE (500 875);
FORCEPROP 2 LAST CDS_LIB mstr_symbols
J 0
(425 875);
PAINT ORANGE (425 875);
DISPLAY INVISIBLE (425 875);
FORCEPROP 1 LAST SIZE 1B
J 0
(500 825);
DISPLAY 0.872340 (500 825);
PAINT AQUA (500 825);
DISPLAY INVISIBLE (500 825);
FORCEPROP 1 LAST HDL_POWER GND
J 0
(425 1025);
DISPLAY 0.872340 (425 1025);
PAINT GREEN (425 1025);
DISPLAY INVISIBLE (425 1025);
FORCEADD CAP..1
(425 1075);
FORCEPROP 1 LASTPIN (425 975) $PN 2
J 0
(435 955);
DISPLAY 0.617021 (435 955);
PAINT ORANGE (435 955);
FORCEPROP 1 LAST MATERIAL X6S
J 0
(475 975);
DISPLAY 0.617021 (475 975);
PAINT SKYBLUE (475 975);
FORCEPROP 1 LAST PACK_TYPE 0603
J 0
(475 875);
DISPLAY 0.617021 (475 875);
PAINT SKYBLUE (475 875);
FORCEPROP 1 LAST PART_NUMBER E15431-003
J 0
(475 925);
DISPLAY 0.617021 (475 925);
PAINT BLUE (475 925);
FORCEPROP 1 LASTPIN (425 1175) $PN 1
J 0
(435 1155);
DISPLAY 0.617021 (435 1155);
PAINT ORANGE (435 1155);
FORCEPROP 1 LAST LOCATION C4A11
J 0
(475 1175);
DISPLAY 0.617021 (475 1175);
PAINT AQUA (475 1175);
FORCEPROP 1 LAST VALUE 4.7UF
J 0
(475 1125);
DISPLAY 0.617021 (475 1125);
PAINT SKYBLUE (475 1125);
FORCEPROP 1 LAST TOLERANCE 10%
J 0
(475 1025);
DISPLAY 0.617021 (475 1025);
PAINT SKYBLUE (475 1025);
FORCEPROP 1 LAST VOLTAGE 6.3V
J 0
(475 1075);
DISPLAY 0.617021 (475 1075);
PAINT SKYBLUE (475 1075);
FORCEPROP 2 LAST CDS_LIB mstr_discrete
J 0
(425 1075);
PAINT ORANGE (425 1075);
DISPLAY INVISIBLE (425 1075);
FORCEPROP 2 LAST CDS_LOCATION C4A11
J 0
(475 1175);
DISPLAY 0.617021 (475 1175);
PAINT AQUA (475 1175);
DISPLAY INVISIBLE (475 1175);
FORCEPROP 1 LAST PATH I46
J 0
(475 1225);
DISPLAY 0.978723 (475 1225);
PAINT WHITE (475 1225);
DISPLAY INVISIBLE (475 1225);
FORCEPROP 2 LAST SEC_TYPE 0603
J 0
(475 1275);
DISPLAY 1.021277 (475 1275);
PAINT ORANGE (475 1275);
DISPLAY INVISIBLE (475 1275);
FORCEPROP 2 LAST SEC 1
J 0
(475 1275);
DISPLAY 0.680851 (475 1275);
PAINT MONO (475 1275);
DISPLAY INVISIBLE (475 1275);
FORCEPROP 0 LAST ROOM VTT_DEF_PWR_VR
J 0
(475 1275);
DISPLAY 1.021277 (475 1275);
PAINT ORANGE (475 1275);
DISPLAY INVISIBLE (475 1275);
FORCEADD CAP_A..1
(3675 3475);
FORCEPROP 1 LASTPIN (3675 3375) $PN 2
J 0
(3685 3355);
DISPLAY 0.617021 (3685 3355);
PAINT ORANGE (3685 3355);
FORCEPROP 1 LASTPIN (3675 3575) $PN 1
J 0
(3685 3555);
DISPLAY 0.617021 (3685 3555);
PAINT ORANGE (3685 3555);
FORCEPROP 1 LAST MATERIAL X5R
J 0
(3725 3375);
DISPLAY 0.617021 (3725 3375);
PAINT SKYBLUE (3725 3375);
FORCEPROP 1 LAST VOLTAGE 4V
J 0
(3725 3475);
DISPLAY 0.617021 (3725 3475);
PAINT SKYBLUE (3725 3475);
FORCEPROP 1 LAST TOLERANCE 20%
J 0
(3725 3425);
DISPLAY 0.617021 (3725 3425);
PAINT SKYBLUE (3725 3425);
FORCEPROP 1 LAST PART_NUMBER 602433-106
J 0
(3725 3325);
DISPLAY 0.617021 (3725 3325);
PAINT BLUE (3725 3325);
FORCEPROP 1 LAST VALUE 47UF
J 0
(3725 3525);
DISPLAY 0.617021 (3725 3525);
PAINT SKYBLUE (3725 3525);
FORCEPROP 1 LAST PACK_TYPE 0603V
J 0
(3725 3275);
DISPLAY 0.617021 (3725 3275);
PAINT SKYBLUE (3725 3275);
FORCEPROP 1 LAST LOCATION C5L4
J 0
(3725 3575);
DISPLAY 0.617021 (3725 3575);
PAINT AQUA (3725 3575);
FORCEPROP 2 LAST CDS_LIB dev_discrete
J 0
(3675 3475);
PAINT ORANGE (3675 3475);
DISPLAY INVISIBLE (3675 3475);
FORCEPROP 2 LAST CDS_LOCATION C5L4
J 0
(3725 3575);
DISPLAY 0.617021 (3725 3575);
PAINT AQUA (3725 3575);
DISPLAY INVISIBLE (3725 3575);
FORCEPROP 2 LAST CDS_SEC 1
J 0
(3725 3625);
PAINT ORANGE (3725 3625);
DISPLAY INVISIBLE (3725 3625);
FORCEPROP 2 LAST SEC_TYPE 0603V
J 0
(3725 3675);
DISPLAY 1.021277 (3725 3675);
PAINT ORANGE (3725 3675);
DISPLAY INVISIBLE (3725 3675);
FORCEPROP 2 LAST SEC 1
J 0
(3725 3675);
DISPLAY 0.680851 (3725 3675);
PAINT MONO (3725 3675);
DISPLAY INVISIBLE (3725 3675);
FORCEPROP 1 LAST PATH I47
J 0
(3725 3625);
DISPLAY 0.978723 (3725 3625);
PAINT WHITE (3725 3625);
DISPLAY INVISIBLE (3725 3625);
FORCEADD CAP_A..1
(4025 3475);
FORCEPROP 1 LASTPIN (4025 3375) $PN 2
J 0
(4035 3355);
DISPLAY 0.617021 (4035 3355);
PAINT ORANGE (4035 3355);
FORCEPROP 1 LASTPIN (4025 3575) $PN 1
J 0
(4035 3555);
DISPLAY 0.617021 (4035 3555);
PAINT ORANGE (4035 3555);
FORCEPROP 1 LAST LOCATION C5M13
J 0
(4075 3575);
DISPLAY 0.617021 (4075 3575);
PAINT AQUA (4075 3575);
FORCEPROP 1 LAST PART_NUMBER 602433-106
J 0
(4075 3325);
DISPLAY 0.617021 (4075 3325);
PAINT BLUE (4075 3325);
FORCEPROP 1 LAST VALUE 47UF
J 0
(4075 3525);
DISPLAY 0.617021 (4075 3525);
PAINT SKYBLUE (4075 3525);
FORCEPROP 1 LAST TOLERANCE 20%
J 0
(4075 3425);
DISPLAY 0.617021 (4075 3425);
PAINT SKYBLUE (4075 3425);
FORCEPROP 1 LAST PACK_TYPE 0603V
J 0
(4075 3275);
DISPLAY 0.617021 (4075 3275);
PAINT SKYBLUE (4075 3275);
FORCEPROP 1 LAST VOLTAGE 4V
J 0
(4075 3475);
DISPLAY 0.617021 (4075 3475);
PAINT SKYBLUE (4075 3475);
FORCEPROP 1 LAST MATERIAL X5R
J 0
(4075 3375);
DISPLAY 0.617021 (4075 3375);
PAINT SKYBLUE (4075 3375);
FORCEPROP 2 LAST CDS_LIB dev_discrete
J 0
(4025 3475);
PAINT ORANGE (4025 3475);
DISPLAY INVISIBLE (4025 3475);
FORCEPROP 2 LAST CDS_LOCATION C5M13
J 0
(4075 3575);
DISPLAY 0.617021 (4075 3575);
PAINT AQUA (4075 3575);
DISPLAY INVISIBLE (4075 3575);
FORCEPROP 2 LAST SEC_TYPE 0603V
J 0
(4075 3675);
DISPLAY 1.021277 (4075 3675);
PAINT ORANGE (4075 3675);
DISPLAY INVISIBLE (4075 3675);
FORCEPROP 2 LAST CDS_SEC 1
J 0
(4075 3625);
PAINT ORANGE (4075 3625);
DISPLAY INVISIBLE (4075 3625);
FORCEPROP 2 LAST SEC 1
J 0
(4075 3675);
DISPLAY 0.680851 (4075 3675);
PAINT MONO (4075 3675);
DISPLAY INVISIBLE (4075 3675);
FORCEPROP 1 LAST PATH I48
J 0
(4075 3625);
DISPLAY 0.978723 (4075 3625);
PAINT WHITE (4075 3625);
DISPLAY INVISIBLE (4075 3625);
FORCEADD CAP_A..1
(4425 3475);
FORCEPROP 1 LAST VALUE 47UF
J 0
(4475 3525);
DISPLAY 0.617021 (4475 3525);
PAINT SKYBLUE (4475 3525);
FORCEPROP 1 LAST TOLERANCE 20%
J 0
(4475 3425);
DISPLAY 0.617021 (4475 3425);
PAINT SKYBLUE (4475 3425);
FORCEPROP 1 LAST VOLTAGE 4V
J 0
(4475 3475);
DISPLAY 0.617021 (4475 3475);
PAINT SKYBLUE (4475 3475);
FORCEPROP 1 LAST MATERIAL X5R
J 0
(4475 3375);
DISPLAY 0.617021 (4475 3375);
PAINT SKYBLUE (4475 3375);
FORCEPROP 1 LASTPIN (4425 3575) $PN 1
J 0
(4435 3555);
DISPLAY 0.617021 (4435 3555);
PAINT ORANGE (4435 3555);
FORCEPROP 1 LASTPIN (4425 3375) $PN 2
J 0
(4435 3355);
DISPLAY 0.617021 (4435 3355);
PAINT ORANGE (4435 3355);
FORCEPROP 1 LAST LOCATION C5L5
J 0
(4475 3575);
DISPLAY 0.617021 (4475 3575);
PAINT AQUA (4475 3575);
FORCEPROP 1 LAST PART_NUMBER 602433-106
J 0
(4475 3325);
DISPLAY 0.617021 (4475 3325);
PAINT BLUE (4475 3325);
FORCEPROP 1 LAST PACK_TYPE 0603V
J 0
(4475 3275);
DISPLAY 0.617021 (4475 3275);
PAINT SKYBLUE (4475 3275);
FORCEPROP 2 LAST CDS_LIB dev_discrete
J 0
(4425 3475);
PAINT ORANGE (4425 3475);
DISPLAY INVISIBLE (4425 3475);
FORCEPROP 2 LAST CDS_LOCATION C5L5
J 0
(4475 3575);
DISPLAY 0.617021 (4475 3575);
PAINT AQUA (4475 3575);
DISPLAY INVISIBLE (4475 3575);
FORCEPROP 2 LAST CDS_SEC 1
J 0
(4475 3625);
PAINT ORANGE (4475 3625);
DISPLAY INVISIBLE (4475 3625);
FORCEPROP 2 LAST SEC_TYPE 0603V
J 0
(4475 3675);
DISPLAY 1.021277 (4475 3675);
PAINT ORANGE (4475 3675);
DISPLAY INVISIBLE (4475 3675);
FORCEPROP 2 LAST SEC 1
J 0
(4475 3675);
DISPLAY 0.680851 (4475 3675);
PAINT MONO (4475 3675);
DISPLAY INVISIBLE (4475 3675);
FORCEPROP 1 LAST PATH I49
J 0
(4475 3625);
DISPLAY 0.978723 (4475 3625);
PAINT WHITE (4475 3625);
DISPLAY INVISIBLE (4475 3625);
FORCEADD RES..1
(4400 1925);
FORCEPROP 1 LASTPIN (4300 1925) $PN 1
J 0
(4312 1937);
DISPLAY 0.617021 (4312 1937);
PAINT ORANGE (4312 1937);
FORCEPROP 1 LAST WATTAGE 1/16W
J 2
(4375 1775);
DISPLAY 0.617021 (4375 1775);
PAINT SKYBLUE (4375 1775);
FORCEPROP 1 LAST VALUE 33.2
J 2
(4375 1825);
DISPLAY 0.617021 (4375 1825);
PAINT SKYBLUE (4375 1825);
FORCEPROP 1 LAST LOCATION R4A6
J 0
(4350 1975);
DISPLAY 0.617021 (4350 1975);
PAINT AQUA (4350 1975);
FORCEPROP 1 LAST MATERIAL CHIP
J 0
(4400 1775);
DISPLAY 0.617021 (4400 1775);
PAINT SKYBLUE (4400 1775);
FORCEPROP 1 LAST TOLERANCE 1%
J 0
(4400 1825);
DISPLAY 0.617021 (4400 1825);
PAINT SKYBLUE (4400 1825);
FORCEPROP 1 LASTPIN (4500 1925) $PN 2
J 0
(4462 1937);
DISPLAY 0.617021 (4462 1937);
PAINT ORANGE (4462 1937);
FORCEPROP 1 LAST PACK_TYPE 0402
J 0
(4650 1775);
DISPLAY 0.617021 (4650 1775);
PAINT SKYBLUE (4650 1775);
FORCEPROP 1 LAST PART_NUMBER G21796-074
J 0
(4350 2025);
DISPLAY 0.617021 (4350 2025);
PAINT BLUE (4350 2025);
FORCEPROP 2 LAST CDS_LOCATION R4A6
J 0
(4350 1975);
DISPLAY 0.617021 (4350 1975);
PAINT AQUA (4350 1975);
DISPLAY INVISIBLE (4350 1975);
FORCEPROP 2 LAST CDS_LIB mstr_discrete
J 0
(4400 1925);
PAINT MONO (4400 1925);
DISPLAY INVISIBLE (4400 1925);
FORCEPROP 2 LAST SEC_TYPE 0402
J 0
(4350 2125);
DISPLAY 1.021277 (4350 2125);
PAINT ORANGE (4350 2125);
DISPLAY INVISIBLE (4350 2125);
FORCEPROP 2 LAST SEC 1
J 0
(4350 2125);
DISPLAY 0.680851 (4350 2125);
PAINT MONO (4350 2125);
DISPLAY INVISIBLE (4350 2125);
FORCEPROP 1 LAST PATH I51
J 0
(4350 2075);
DISPLAY 0.978723 (4350 2075);
PAINT WHITE (4350 2075);
DISPLAY INVISIBLE (4350 2075);
FORCEADD RES..1
R 1
(5025 1125);
FORCEPROP 1 LAST LOCATION R4A1
R 1
J 0
(4975 1075);
DISPLAY 0.617021 (4975 1075);
PAINT AQUA (4975 1075);
FORCEPROP 1 LAST PART_NUMBER G21796-208
R 1
J 0
(4925 1075);
DISPLAY 0.617021 (4925 1075);
PAINT BLUE (4925 1075);
FORCEPROP 1 LAST VALUE 51.1
R 1
J 2
(5125 1100);
DISPLAY 0.617021 (5125 1100);
PAINT SKYBLUE (5125 1100);
FORCEPROP 1 LAST TOLERANCE 1.0%
R 1
J 0
(5125 1125);
DISPLAY 0.617021 (5125 1125);
PAINT SKYBLUE (5125 1125);
FORCEPROP 1 LAST WATTAGE 1/16W
R 1
J 2
(5175 1100);
DISPLAY 0.617021 (5175 1100);
PAINT SKYBLUE (5175 1100);
FORCEPROP 1 LAST PACK_TYPE 0402
R 1
J 0
(5175 1250);
DISPLAY 0.617021 (5175 1250);
PAINT SKYBLUE (5175 1250);
FORCEPROP 1 LAST MATERIAL CHIP
R 1
J 0
(5175 1125);
DISPLAY 0.617021 (5175 1125);
PAINT SKYBLUE (5175 1125);
FORCEPROP 1 LAST PATH I52
R 1
J 0
(4875 1075);
DISPLAY 0.978723 (4875 1075);
PAINT WHITE (4875 1075);
DISPLAY INVISIBLE (4875 1075);
FORCEPROP 2 LAST CDS_LOCATION R4A1
R 1
J 0
(4975 1075);
DISPLAY 0.617021 (4975 1075);
PAINT AQUA (4975 1075);
DISPLAY INVISIBLE (4975 1075);
FORCEPROP 1 LASTPIN (5025 1025) $PN 1
R 1
J 0
(5013 1037);
DISPLAY 0.787234 (5013 1037);
PAINT ORANGE (5013 1037);
DISPLAY INVISIBLE (5013 1037);
FORCEPROP 1 LASTPIN (5025 1225) $PN 2
R 1
J 0
(5013 1187);
DISPLAY 0.787234 (5013 1187);
PAINT ORANGE (5013 1187);
DISPLAY INVISIBLE (5013 1187);
FORCEPROP 2 LAST CDS_LIB mstr_discrete
J 0
(5025 1125);
PAINT ORANGE (5025 1125);
DISPLAY INVISIBLE (5025 1125);
FORCEPROP 2 LAST CDS_SEC 1
J 0
(5050 1250);
PAINT MONO (5050 1250);
DISPLAY INVISIBLE (5050 1250);
FORCEPROP 2 LAST $SEC 1
J 0
(5050 1250);
PAINT MONO (5050 1250);
DISPLAY INVISIBLE (5050 1250);
FORCEADD SHUNT..1
(5100 125);
FORCEPROP 1 LASTPIN (4950 125) $PN 1
J 2
(5000 135);
DISPLAY 0.617021 (5000 135);
PAINT ORANGE (5000 135);
FORCEPROP 1 LAST PART_NUMBER N_A
J 0
(5025 35);
DISPLAY 0.617021 (5025 35);
PAINT BLUE (5025 35);
FORCEPROP 1 LAST LOCATION SH5L1
J 0
(5025 175);
DISPLAY 0.617021 (5025 175);
PAINT AQUA (5025 175);
FORCEPROP 1 LASTPIN (5250 125) $PN 2
J 0
(5210 135);
DISPLAY 0.617021 (5210 135);
PAINT ORANGE (5210 135);
FORCEPROP 1 LAST PACK_TYPE SH0201
J 0
(5040 -60);
DISPLAY 0.978723 (5040 -60);
PAINT SKYBLUE (5040 -60);
DISPLAY INVISIBLE (5040 -60);
FORCEPROP 1 LAST PIN_SHORT A:B
J 0
(5025 -125);
DISPLAY 1.021277 (5025 -125);
PAINT ORANGE (5025 -125);
DISPLAY INVISIBLE (5025 -125);
FORCEPROP 1 LAST MATERIAL EMPTY
J 0
(5025 -10);
DISPLAY 0.978723 (5025 -10);
PAINT RED (5025 -10);
DISPLAY INVISIBLE (5025 -10);
FORCEPROP 2 LAST CDS_LIB mstr_misc
J 0
(5100 125);
PAINT ORANGE (5100 125);
DISPLAY INVISIBLE (5100 125);
FORCEPROP 0 LAST SEC 1
J 0
(5025 225);
DISPLAY 0.680851 (5025 225);
PAINT MONO (5025 225);
DISPLAY INVISIBLE (5025 225);
FORCEPROP 1 LAST PATH I53
J 0
(5050 225);
DISPLAY 0.978723 (5050 225);
PAINT ORANGE (5050 225);
DISPLAY INVISIBLE (5050 225);
FORCEPROP 2 LAST SEC_TYPE SH0201
J 0
(5050 275);
DISPLAY 1.021277 (5050 275);
PAINT ORANGE (5050 275);
DISPLAY INVISIBLE (5050 275);
FORCEADD PVTT_DEF..1
(3675 3750);
FORCEPROP 3 LASTPIN (3675 3700) SIG_NAME PVTT_DEF\g
J 0
(3685 3710);
DISPLAY 0.659574 (3685 3710);
PAINT MONO (3685 3710);
DISPLAY INVISIBLE (3685 3710);
FORCEPROP 1 LAST VOLTAGE 0.6V
J 0
(3630 3707);
DISPLAY 0.340426 (3630 3707);
PAINT SKYBLUE (3630 3707);
DISPLAY INVISIBLE (3630 3707);
FORCEPROP 1 LAST BODY_TYPE PLUMBING
J 0
(3630 3707);
DISPLAY 0.340426 (3630 3707);
PAINT GREEN (3630 3707);
DISPLAY INVISIBLE (3630 3707);
FORCEPROP 2 LAST CDS_LIB mstr_symbols
J 0
(3675 3750);
PAINT ORANGE (3675 3750);
DISPLAY INVISIBLE (3675 3750);
FORCEPROP 1 LAST HDL_POWER PVTT_DEF
J 1
(3675 3800);
DISPLAY 0.872340 (3675 3800);
PAINT GREEN (3675 3800);
DISPLAY INVISIBLE (3675 3800);
FORCEPROP 1 LAST PATH I6
J 0
(3725 3775);
DISPLAY 0.872340 (3725 3775);
PAINT AQUA (3725 3775);
DISPLAY INVISIBLE (3725 3775);
FORCEPROP 2 LAST BOM_COST MEM_VRD_PVDDQ_AB
J 0
(3750 3850);
PAINT MONO (3750 3850);
DISPLAY INVISIBLE (3750 3850);
FORCEPROP 2 LAST ROOM VTT_DEF_PWR_VR
J 0
(3925 3850);
PAINT ORANGE (3925 3850);
DISPLAY INVISIBLE (3925 3850);
FORCEADD GND..1
(4525 3075);
FORCEPROP 3 LASTPIN (4525 3125) SIG_NAME GND\g
J 0
(4535 3135);
DISPLAY 0.659574 (4535 3135);
PAINT MONO (4535 3135);
DISPLAY INVISIBLE (4535 3135);
FORCEPROP 2 LAST ROOM VTT_DEF_PWR_VR
J 0
(3975 3150);
PAINT ORANGE (3975 3150);
DISPLAY INVISIBLE (3975 3150);
FORCEPROP 1 LAST VOLTAGE 0.0V
J 0
(4480 3032);
DISPLAY 0.340426 (4480 3032);
PAINT SKYBLUE (4480 3032);
DISPLAY INVISIBLE (4480 3032);
FORCEPROP 1 LAST SIZE 1B
J 0
(4600 3025);
DISPLAY 0.893617 (4600 3025);
PAINT GREEN (4600 3025);
DISPLAY INVISIBLE (4600 3025);
FORCEPROP 1 LAST BODY_TYPE PLUMBING
J 0
(4480 3032);
DISPLAY 0.340426 (4480 3032);
PAINT GREEN (4480 3032);
DISPLAY INVISIBLE (4480 3032);
FORCEPROP 2 LAST BOM_COST MEM_VRD_PVDDQ_AB
J 0
(4200 3150);
PAINT MONO (4200 3150);
DISPLAY INVISIBLE (4200 3150);
FORCEPROP 1 LAST HDL_POWER GND
J 0
(4525 3225);
DISPLAY 0.893617 (4525 3225);
PAINT GREEN (4525 3225);
DISPLAY INVISIBLE (4525 3225);
FORCEPROP 1 LAST PATH I8
J 0
(4600 3075);
DISPLAY 0.872340 (4600 3075);
PAINT AQUA (4600 3075);
DISPLAY INVISIBLE (4600 3075);
FORCEPROP 2 LAST CDS_LIB mstr_symbols
J 0
(4525 3075);
PAINT ORANGE (4525 3075);
DISPLAY INVISIBLE (4525 3075);
FORCEADD PVTT_DEF..1
(5675 1675);
FORCEPROP 3 LASTPIN (5675 1625) SIG_NAME PVTT_DEF\g
J 0
(5685 1635);
DISPLAY 0.659574 (5685 1635);
PAINT MONO (5685 1635);
DISPLAY INVISIBLE (5685 1635);
FORCEPROP 1 LAST VOLTAGE 0.6V
J 0
(5630 1632);
DISPLAY 0.340426 (5630 1632);
PAINT SKYBLUE (5630 1632);
DISPLAY INVISIBLE (5630 1632);
FORCEPROP 1 LAST BODY_TYPE PLUMBING
J 0
(5630 1632);
DISPLAY 0.340426 (5630 1632);
PAINT GREEN (5630 1632);
DISPLAY INVISIBLE (5630 1632);
FORCEPROP 1 LAST HDL_POWER PVTT_DEF
J 1
(5675 1725);
DISPLAY 0.872340 (5675 1725);
PAINT GREEN (5675 1725);
DISPLAY INVISIBLE (5675 1725);
FORCEPROP 1 LAST PATH I9
J 0
(5725 1700);
DISPLAY 0.872340 (5725 1700);
PAINT AQUA (5725 1700);
DISPLAY INVISIBLE (5725 1700);
FORCEPROP 2 LAST CDS_LIB mstr_symbols
J 0
(5675 1675);
PAINT ORANGE (5675 1675);
DISPLAY INVISIBLE (5675 1675);
FORCEADD CAD_NOTE..1
(4875 -150);
FORCEPROP 0 LAST L1 PLACE NEAR CENTER
J 0
(4757 -245);
DISPLAY 0.617021 (4757 -245);
PAINT WHITE (4757 -245);
FORCEPROP 0 LAST L2 OF PVTT PLANE
J 0
(4757 -297);
DISPLAY 0.617021 (4757 -297);
PAINT WHITE (4757 -297);
FORCEPROP 1 LAST COMMENT_BODY TRUE
J 0
(4900 -50);
DISPLAY 0.978723 (4900 -50);
PAINT ORANGE (4900 -50);
DISPLAY INVISIBLE (4900 -50);
FORCEPROP 2 LAST CDS_LIB mstr_symbols
J 0
(4875 -150);
PAINT ORANGE (4875 -150);
DISPLAY INVISIBLE (4875 -150);
FORCEADD PRELIM..6
(1685 1140);
PAINT GRAY (1685 1140);
FORCEPROP 2 LAST CDS_LIB mstr_misc
J 0
(1685 1140);
PAINT ORANGE (1685 1140);
DISPLAY INVISIBLE (1685 1140);
FORCEPROP 1 LAST COMMENT_BODY TRUE
J 0
(1685 1140);
PAINT ORANGE (1685 1140);
DISPLAY INVISIBLE (1685 1140);
FORCEADD CAD_NOTE..1
(4900 325);
FORCEPROP 0 LAST L1 SPOF
J 0
(4761 176);
DISPLAY 0.617021 (4761 176);
PAINT WHITE (4761 176);
FORCEPROP 2 LAST CDS_LIB mstr_symbols
J 0
(4900 325);
PAINT ORANGE (4900 325);
DISPLAY INVISIBLE (4900 325);
FORCEPROP 1 LAST COMMENT_BODY TRUE
J 0
(4925 425);
DISPLAY 0.978723 (4925 425);
PAINT ORANGE (4925 425);
DISPLAY INVISIBLE (4925 425);
FORCEADD CAD_NOTE..1
(4875 3700);
FORCEPROP 2 LAST CDS_LIB mstr_symbols
J 0
(4875 3700);
PAINT ORANGE (4875 3700);
DISPLAY INVISIBLE (4875 3700);
FORCEPROP 1 LAST COMMENT_BODY TRUE
J 0
(4900 3800);
DISPLAY 0.978723 (4900 3800);
PAINT ORANGE (4900 3800);
DISPLAY INVISIBLE (4900 3800);
FORCEADD DNS..2
(-170 745);
PAINT RED (-170 745);
FORCEPROP 1 LAST COMMENT_BODY TRUE
R 1
J 0
(-95 520);
DISPLAY 0.872340 (-95 520);
PAINT GREEN (-95 520);
DISPLAY INVISIBLE (-95 520);
FORCEPROP 2 LAST CDS_LIB mstr_misc
J 0
(-170 745);
PAINT ORANGE (-170 745);
DISPLAY INVISIBLE (-170 745);
FORCEADD DNS..2
(-220 -305);
PAINT RED (-220 -305);
FORCEPROP 1 LAST COMMENT_BODY TRUE
R 1
J 0
(-145 -530);
DISPLAY 0.872340 (-145 -530);
PAINT GREEN (-145 -530);
DISPLAY INVISIBLE (-145 -530);
FORCEPROP 2 LAST CDS_LIB mstr_misc
J 0
(-220 -305);
PAINT ORANGE (-220 -305);
DISPLAY INVISIBLE (-220 -305);
FORCEADD CAD_NOTE..1
(250 2850);
FORCEPROP 0 LAST L1 PLACE CLOSE TO CONTROLLER
J 0
(163 2758);
DISPLAY 0.617021 (163 2758);
PAINT WHITE (163 2758);
FORCEPROP 2 LAST CDS_LIB mstr_symbols
J 0
(250 2850);
PAINT ORANGE (250 2850);
DISPLAY INVISIBLE (250 2850);
FORCEPROP 1 LAST COMMENT_BODY TRUE
J 0
(275 2950);
DISPLAY 0.978723 (275 2950);
PAINT ORANGE (275 2950);
DISPLAY INVISIBLE (275 2950);
FORCEADD CAD_NOTE..1
(2400 1675);
FORCEPROP 0 LAST L1 PLACE CLOSE TO CONTROLLER
J 0
(2218 1583);
DISPLAY 0.617021 (2218 1583);
PAINT WHITE (2218 1583);
FORCEPROP 1 LAST COMMENT_BODY TRUE
J 0
(2425 1775);
DISPLAY 0.978723 (2425 1775);
PAINT ORANGE (2425 1775);
DISPLAY INVISIBLE (2425 1775);
FORCEPROP 2 LAST CDS_LIB mstr_symbols
J 0
(2400 1675);
PAINT ORANGE (2400 1675);
DISPLAY INVISIBLE (2400 1675);
FORCEADD DNS..3
(5105 120);
PAINT RED (5105 120);
FORCEPROP 1 LAST COMMENT_BODY TRUE
R 1
J 0
(5180 -105);
DISPLAY 0.872340 (5180 -105);
PAINT GREEN (5180 -105);
DISPLAY INVISIBLE (5180 -105);
FORCEPROP 2 LAST CDS_LIB mstr_misc
J 0
(5105 120);
PAINT ORANGE (5105 120);
DISPLAY INVISIBLE (5105 120);
FORCEADD INTEL_CORP_BPAGE..1
(6025 -1075);
FORCEPROP 1 LAST CDS_CON_LAST_MODIFIED Tue Dec 01 11:52:26 2015
J 0
(4600 -750);
PAINT GREEN (4600 -750);
DISPLAY INVISIBLE (4600 -750);
FORCEPROP 1 LAST CUSTOM_TXT_CDS <CURRENT_DESIGN_SHEET> OF <TOTAL_DESIGN_SHEETS>
J 0
(5525 -1050);
PAINT GREEN (5525 -1050);
FORCEPROP 1 LAST CUSTOM_TXT_CDS <CON_LAST_MODIFIED>
J 0
(4100 -725);
PAINT GREEN (4100 -725);
FORCEPROP 2 LAST CUSTOM_TXT_CDS <XR_PAGE_TITLE>
J 0
(-1865 4175);
DISPLAY 0.638298 (-1865 4175);
PAINT PINK (-1865 4175);
DISPLAY INVISIBLE (-1865 4175);
FORCEPROP 1 LAST SCH_TITLE DDR VTT VR CHANNEL DEF
J 0
(-1925 -1025);
DISPLAY 1.212766 (-1925 -1025);
PAINT GREEN (-1925 -1025);
FORCEPROP 1 LAST SCH_ADDRESS3 SANTA CLARA, CA 95052-8119
J 0
(2050 -1050);
DISPLAY 0.617021 (2050 -1050);
PAINT GREEN (2050 -1050);
FORCEPROP 1 LAST SCH_ADDRESS2 P.O. BOX 58119
J 0
(2050 -1000);
DISPLAY 0.617021 (2050 -1000);
PAINT GREEN (2050 -1000);
FORCEPROP 1 LAST SCH_ADDRESS1 2200 MISSION COLLEGE BLVD.
J 0
(2050 -950);
DISPLAY 0.617021 (2050 -950);
PAINT GREEN (2050 -950);
FORCEPROP 1 LAST SCH_NUMBER H4694802
J 0
(4725 -925);
DISPLAY 1.212766 (4725 -925);
PAINT YELLOW (4725 -925);
FORCEPROP 1 LAST SCH_DEPT BESD
J 1
(1575 -975);
DISPLAY 1.212766 (1575 -975);
PAINT YELLOW (1575 -975);
FORCEPROP 1 LAST SCH_REV 2.420
J 0
(5775 -925);
DISPLAY 0.978723 (5775 -925);
PAINT YELLOW (5775 -925);
FORCEPROP 2 LAST PAGE_BORDER TRUE
J 0
(-1865 4175);
DISPLAY 0.659574 (-1865 4175);
PAINT PINK (-1865 4175);
DISPLAY INVISIBLE (-1865 4175);
FORCEPROP 2 LAST CDS_LIB mstr_symbols
J 0
(6025 -1075);
PAINT ORANGE (6025 -1075);
DISPLAY INVISIBLE (6025 -1075);
FORCEPROP 1 LAST COMMENT_BODY TRUE
J 0
(6037 -1063);
DISPLAY 0.446809 (6037 -1063);
PAINT GREEN (6037 -1063);
DISPLAY INVISIBLE (6037 -1063);
FORCEPROP 2 LAST CDS_XR_PAGE_TITLE CR-222 : @BASEBOARD_FAB2_LIB.BASEBOARD_FAB2(SCH_1):PAGE222
J 0
(-1865 4175);
DISPLAY 0.638298 (-1865 4175);
PAINT PINK (-1865 4175);
DISPLAY INVISIBLE (-1865 4175);
WIRE 16 -1 (4000 1525)(4000 1625);
WIRE 16 -1 (5025 1025)(5025 875);
WIRE 16 -1 (5025 875)(4125 875);
WIRE 16 -1 (4125 875)(4125 1025);
WIRE 16 -1 (4125 775)(4125 875);
WIRE 16 -1 (2550 725)(2550 850);
WIRE 16 -1 (2000 1000)(2150 1000);
WIRE 16 -1 (2150 1000)(2150 950);
WIRE 16 -1 (2000 950)(2150 950);
WIRE 16 -1 (2150 950)(2150 850);
WIRE 16 -1 (2000 850)(2150 850);
WIRE 16 -1 (2150 850)(2150 725);
WIRE 16 -1 (600 2250)(600 2375);
WIRE 16 -1 (175 2350)(175 2250);
WIRE 16 -1 (600 1500)(600 1400);
WIRE 16 -1 (1400 1400)(1225 1400);
WIRE 16 -1 (1225 1400)(1225 2625);
WIRE 16 -1 (600 2625)(1225 2625);
WIRE 16 -1 (600 2575)(600 2625);
WIRE 16 -1 (175 2625)(600 2625);
WIRE 16 -1 (175 2550)(175 2625);
WIRE 16 -1 (175 2625)(-850 2625);
WIRE 16 -1 (-850 2625)(-850 1650);
WIRE 16 -1 (-850 2625)(-1300 2625);
WIRE 16 -1 (-1300 2825)(-1300 2625);
WIRE 16 -1 (-675 1650)(-850 1650);
WIRE 16 -1 (-225 -475)(-225 -400);
WIRE 16 -1 (175 1850)(-175 1850);
WIRE 16 -1 (-175 1850)(-450 1850);
WIRE 16 -1 (-175 850)(-175 1850);
WIRE 16 -1 (-450 2200)(-450 1850);
WIRE 16 -1 (3575 2375)(3575 2200);
WIRE 16 -1 (425 925)(425 975);
WIRE 16 -1 (4425 3575)(4425 3650);
WIRE 16 -1 (4425 3650)(4025 3650);
WIRE 16 -1 (4025 3575)(4025 3650);
WIRE 16 -1 (3675 3650)(4025 3650);
WIRE 16 -1 (3675 3650)(3675 3700);
WIRE 16 -1 (3675 3650)(3675 3575);
WIRE 16 -1 (3675 3375)(3675 3225);
WIRE 16 -1 (3675 3225)(4025 3225);
WIRE 16 -1 (4025 3375)(4025 3225);
WIRE 16 -1 (4025 3225)(4425 3225);
WIRE 16 -1 (4425 3375)(4425 3225);
WIRE 16 -1 (4425 3225)(4525 3225);
WIRE 16 -1 (4525 3125)(4525 3225);
WIRE 16 -1 (4125 1225)(4125 1400);
WIRE 16 -1 (5025 1400)(4125 1400);
WIRE 16 -1 (2000 1400)(4125 1400);
WIRE 16 -1 (5025 1225)(5025 1400);
WIRE 16 -1 (5675 1400)(5025 1400);
WIRE 16 -1 (5675 125)(5675 1400);
WIRE 16 -1 (5675 1625)(5675 1400);
WIRE 16 -1 (5250 125)(5675 125);
WIRE 16 2175 (5975 3000)(5975 3875);
WIRE 16 2175 (5975 3000)(3525 3000);
WIRE 16 2175 (5975 3875)(3525 3875);
WIRE 16 2175 (3525 3000)(3525 3875);
WIRE 16 -1 (5475 1925)(4500 1925);
FORCEPROP 2 LAST SIG_NAME PWRGD_PVTT_CPU0
J 0
(4925 1935);
DISPLAY 0.617021 (4925 1935);
PAINT ORANGE (4925 1935);
WIRE 16 2175 (5350 -350)(5350 250);
WIRE 16 2175 (4700 -350)(5350 -350);
WIRE 16 2175 (4700 250)(5350 250);
WIRE 16 2175 (4700 -350)(4700 250);
WIRE 16 -1 (2000 1100)(3600 1100);
WIRE 16 -1 (3600 1100)(3600 1925);
WIRE 16 -1 (4000 1925)(3600 1925);
FORCEPROP 2 LAST SIG_NAME PWRGD_PVTT_DEF_CPU0_R
J 0
(3700 1935);
DISPLAY 0.617021 (3700 1935);
PAINT ORANGE (3700 1935);
FORCEPROP 2 LASTPROP $XRERR UNIQUE?
J 0
(3460 1935);
DISPLAY 0.638298 (3460 1935);
PAINT MONO (3460 1935);
DISPLAY INVISIBLE (3460 1935);
WIRE 16 -1 (3575 1925)(3600 1925);
WIRE 16 -1 (3575 2000)(3575 1925);
WIRE 16 -1 (4300 1925)(4000 1925);
WIRE 16 -1 (4000 1825)(4000 1925);
WIRE 16 -1 (4950 125)(950 125);
FORCEPROP 2 LAST SIG_NAME VR_PVTT_DEF_SNS
J 0
(990 130);
DISPLAY 0.617021 (990 130);
PAINT ORANGE (990 130);
FORCEPROP 2 LASTPROP $XRERR UNIQUE?
J 0
(750 130);
DISPLAY 0.638298 (750 130);
PAINT MONO (750 130);
DISPLAY INVISIBLE (750 130);
WIRE 16 -1 (950 1050)(950 125);
WIRE 16 -1 (1400 1050)(950 1050);
WIRE 16 273 (2450 3675)(2450 3175);
WIRE 16 273 (2450 3775)(2450 3675);
WIRE 16 273 (1300 3675)(2450 3675);
WIRE 16 273 (2450 3175)(1300 3175);
WIRE 16 273 (1300 3175)(1300 3675);
WIRE 16 273 (1300 3675)(1300 3775);
WIRE 16 273 (1300 3775)(2450 3775);
WIRE 16 2175 (2200 1750)(3000 1750);
WIRE 16 2175 (2200 625)(2200 1750);
WIRE 16 2175 (3000 1750)(3000 625);
WIRE 16 2175 (3000 625)(2200 625);
WIRE 16 -1 (2550 1050)(2550 1300);
WIRE 16 -1 (2000 1300)(2550 1300);
FORCEPROP 2 LAST SIG_NAME VR_PVTT_DEF_VREF
J 0
(2106 1310);
DISPLAY 0.617021 (2106 1310);
PAINT ORANGE (2106 1310);
FORCEPROP 2 LASTPROP $XRERR UNIQUE?
J 0
(1866 1310);
DISPLAY 0.638298 (1866 1310);
PAINT MONO (1866 1310);
DISPLAY INVISIBLE (1866 1310);
WIRE 16 2175 (1025 1325)(1025 2925);
WIRE 16 2175 (100 1325)(1025 1325);
WIRE 16 2175 (100 2925)(1025 2925);
WIRE 16 2175 (100 1325)(100 2925);
WIRE 16 -1 (1400 900)(1150 900);
WIRE 16 -1 (1150 900)(1150 1850);
WIRE 16 -1 (1150 1850)(600 1850);
WIRE 16 -1 (600 1700)(600 1850);
WIRE 16 -1 (375 1850)(600 1850);
FORCEPROP 2 LAST SIG_NAME VR_PVTT_DEF_BIAS
J 0
(445 1870);
DISPLAY 0.617021 (445 1870);
PAINT ORANGE (445 1870);
FORCEPROP 2 LASTPROP $XRERR UNIQUE?
J 0
(205 1870);
DISPLAY 0.638298 (205 1870);
PAINT MONO (205 1870);
DISPLAY INVISIBLE (205 1870);
WIRE 16 -1 (425 1175)(425 1250);
WIRE 16 -1 (1400 1250)(425 1250);
FORCEPROP 2 LAST SIG_NAME VSENSE_PVDDQ_DEF_VTT
J 0
(655 1260);
DISPLAY 0.617021 (655 1260);
PAINT ORANGE (655 1260);
FORCEPROP 2 LASTPROP $XRERR UNIQUE?
J 0
(415 1260);
DISPLAY 0.638298 (415 1260);
PAINT MONO (415 1260);
DISPLAY INVISIBLE (415 1260);
WIRE 16 -1 (425 1250)(-350 1250);
WIRE 16 -1 (-350 1250)(-350 1650);
WIRE 16 -1 (-350 1650)(-475 1650);
WIRE 16 -1 (1400 1150)(725 1150);
FORCEPROP 2 LAST SIG_NAME FM_PVTT_DEF_EN_R
J 0
(124 240);
DISPLAY 0.617021 (124 240);
PAINT ORANGE (124 240);
FORCEPROP 2 LASTPROP $XRERR UNIQUE?
J 0
(-116 240);
DISPLAY 0.638298 (-116 240);
PAINT MONO (-116 240);
DISPLAY INVISIBLE (-116 240);
WIRE 16 -1 (725 1150)(725 225);
WIRE 16 -1 (725 225)(-175 225);
WIRE 16 -1 (-175 225)(-175 650);
WIRE 16 -1 (-175 225)(-225 225);
WIRE 16 -1 (-275 225)(-225 225);
WIRE 16 -1 (-225 -200)(-225 225);
WIRE 16 -1 (-475 225)(-1225 225);
FORCEPROP 2 LAST SIG_NAME PWRGD_PVDDQ_DEF
J 0
(-1175 240);
DISPLAY 0.617021 (-1175 240);
PAINT ORANGE (-1175 240);
DOT 1 (-175 225);
DOT 1 (-225 225);
DOT 1 (-175 1850);
DOT 1 (-850 2625);
DOT 1 (425 1250);
DOT 1 (600 1850);
DOT 1 (175 2625);
DOT 1 (600 2625);
DOT 1 (1300 3675);
DOT 1 (2150 850);
DOT 1 (2150 950);
DOT 1 (3600 1925);
DOT 1 (4000 1925);
DOT 1 (2450 3675);
DOT 1 (4025 3225);
DOT 1 (3675 3650);
DOT 1 (4025 3650);
DOT 1 (4125 875);
DOT 1 (4125 1400);
DOT 1 (5025 1400);
DOT 1 (5675 1400);
DOT 1 (4425 3225);
FORCENOTE
BOM_COST = MEM_VRD_VTT_DEF
(-1930 -901) 0;
DISPLAY LEFT (-1930 -901);
DISPLAY 1.255319 (-1930 -901);
PAINT PURPLE (-1930 -901);
FORCENOTE
ROOM = VTT_DEF_PWR_VR
(-1930 -826) 0;
DISPLAY LEFT (-1930 -826);
DISPLAY 1.255319 (-1930 -826);
PAINT PURPLE (-1930 -826);
FORCENOTE
CRTICAL: PLACE 0 OHM NEAR  VDDQ SENSE RESISTOR.
(-1668 1484) 0;
DISPLAY LEFT (-1668 1484);
DISPLAY 1.021277 (-1668 1484);
PAINT PURPLE (-1668 1484);
FORCENOTE
IOUT PEAK=+-/1.7A
(1343 3399) 0;
DISPLAY LEFT (1343 3399);
DISPLAY 0.808511 (1343 3399);
PAINT PURPLE (1343 3399);
FORCENOTE
IOUT TDC=+/-1.7A
(1343 3349) 0;
DISPLAY LEFT (1343 3349);
DISPLAY 0.808511 (1343 3349);
PAINT PURPLE (1343 3349);
FORCENOTE
IOUT DI/DT=6A/US
(1343 3249) 0;
DISPLAY LEFT (1343 3249);
DISPLAY 0.808511 (1343 3249);
PAINT PURPLE (1343 3249);
FORCENOTE
DC TOL= +/-1.5%
(1343 3499) 0;
DISPLAY LEFT (1343 3499);
DISPLAY 0.808511 (1343 3499);
PAINT PURPLE (1343 3499);
FORCENOTE
VOUT=0.5 VDDQ
(1343 3599) 0;
DISPLAY LEFT (1343 3599);
DISPLAY 0.808511 (1343 3599);
PAINT PURPLE (1343 3599);
FORCENOTE
IOUT STEP=+ 1.523A / -1.546A
(1343 3299) 0;
DISPLAY LEFT (1343 3299);
DISPLAY 0.808511 (1343 3299);
PAINT PURPLE (1343 3299);
FORCENOTE
AC & RIPPLE=+3.5/-7.3%
(1343 3449) 0;
DISPLAY LEFT (1343 3449);
DISPLAY 0.808511 (1343 3449);
PAINT PURPLE (1343 3449);
FORCENOTE
RIPPLE GUIDELINE= +/-1%
(1343 3549) 0;
DISPLAY LEFT (1343 3549);
DISPLAY 0.808511 (1343 3549);
PAINT PURPLE (1343 3549);
FORCENOTE
PVTT DDR SPECIFICATION:
(1343 3699) 0;
DISPLAY LEFT (1343 3699);
PAINT PURPLE (1343 3699);
FORCENOTE
PLACE BETWEEN DIMMS
(4746 3562) 0;
DISPLAY LEFT (4746 3562);
DISPLAY 1.021277 (4746 3562);
PAINT PURPLE (4746 3562);
QUIT
